G04 ================== begin FILE IDENTIFICATION RECORD ==================*
G04 Layout Name:  D:/<user>/Wistron_project/16316-1/gbr-0621/16316-1.brd*
G04 Film Name:    L7GND*
G04 File Format:  Gerber RS274X*
G04 File Origin:  Cadence Allegro 16.5-S056*
G04 Origin Date:  Wed Jun 21 09:32:16 2017*
G04 *
G04 Layer:  VIA CLASS/L7GND*
G04 Layer:  PIN/L7GND*
G04 Layer:  ETCH/L7GND*
G04 Layer:  DRAWING FORMAT/LAYER_PCB_STORY*
G04 Layer:  DRAWING FORMAT/LAYER_L7GND*
G04 *
G04 Offset:    (0.00 0.00)*
G04 Mirror:    No*
G04 Mode:      Negative*
G04 Rotation:  0*
G04 FullContactRelief:  No*
G04 UndefLineWidth:     6.00*
G04 ================== end FILE IDENTIFICATION RECORD ====================*
%FSLAX35Y35*MOIN*%
%IR0*IPPOS*OFA0.00000B0.00000*MIA0B0*SFA1.00000B1.00000*%
%AMMACRO17*
4,1,16,.07474,.04645,
.08167,.032766,
.086119,.018086,
.087952,.002857,
.087112,-.012459,
.083625,-.027397,
.077597,-.041502,
.07474,-.04645,
.07836,-.05008,
.085866,-.035712,
.090763,-.020259,
.092902,-.004191,
.092218,.012005,
.088732,.027836,
.082551,.042822,
.07836,.05008,
.07474,.04645,
0.0*
4,1,16,.04645,-.07474,
.032766,-.08167,
.018086,-.086119,
.002857,-.087952,
-.012459,-.087112,
-.027397,-.083625,
-.041502,-.077597,
-.04645,-.07474,
-.05008,-.07836,
-.035712,-.085866,
-.020259,-.090763,
-.004191,-.092902,
.012005,-.092218,
.027836,-.088732,
.042822,-.082551,
.05008,-.07836,
.04645,-.07474,
0.0*
4,1,16,-.07474,-.04645,
-.08167,-.032766,
-.086119,-.018086,
-.087952,-.002857,
-.087112,.012459,
-.083625,.027397,
-.077597,.041502,
-.07474,.04645,
-.07836,.05008,
-.085866,.035712,
-.090763,.020259,
-.092902,.004191,
-.092218,-.012005,
-.088732,-.027836,
-.082551,-.042822,
-.07836,-.05008,
-.07474,-.04645,
0.0*
4,1,16,-.04645,.07474,
-.032766,.08167,
-.018086,.086119,
-.002857,.087952,
.012459,.087112,
.027397,.083625,
.041502,.077597,
.04645,.07474,
.05008,.07836,
.035712,.085866,
.020259,.090763,
.004191,.092902,
-.012005,.092218,
-.027836,.088732,
-.042822,.082551,
-.05008,.07836,
-.04645,.07474,
0.0*
%
%ADD17MACRO17*%
%ADD14C,.03*%
%ADD15C,.04*%
%ADD16C,.032*%
%ADD31C,.043*%
%ADD24C,.07*%
%ADD22C,.036*%
%ADD33C,.028*%
%ADD25C,.058*%
%AMMACRO23*
4,1,15,.00398,.00044,
.003999,.000208,
.004004,-.000025,
.003996,-.000258,
.00398,-.00044,
.00483,-.00129,
.004897,-.001007,
.004947,-.000721,
.004981,-.000432,
.004997,-.000141,
.004997,.000149,
.00498,.00044,
.004946,.000729,
.004895,.001015,
.00483,.00129,
.00398,.00044,
90.*
4,1,15,.00044,-.00398,
.000208,-.003999,
-.000025,-.004004,
-.000258,-.003996,
-.00044,-.00398,
-.00129,-.00483,
-.001007,-.004897,
-.000721,-.004947,
-.000432,-.004981,
-.000141,-.004997,
.000149,-.004997,
.00044,-.00498,
.000729,-.004946,
.001015,-.004895,
.00129,-.00483,
.00044,-.00398,
90.*
4,1,15,-.00398,-.00044,
-.003999,-.000208,
-.004004,.000025,
-.003996,.000258,
-.00398,.00044,
-.00483,.00129,
-.004897,.001007,
-.004947,.000721,
-.004981,.000432,
-.004997,.000141,
-.004997,-.000149,
-.00498,-.00044,
-.004946,-.000729,
-.004895,-.001015,
-.00483,-.00129,
-.00398,-.00044,
90.*
4,1,15,-.00044,.00398,
-.000208,.003999,
.000025,.004004,
.000258,.003996,
.00044,.00398,
.00129,.00483,
.001007,.004897,
.000721,.004947,
.000432,.004981,
.000141,.004997,
-.000149,.004997,
-.00044,.00498,
-.000729,.004946,
-.001015,.004895,
-.00129,.00483,
-.00044,.00398,
90.*
%
%ADD23MACRO23*%
%AMMACRO26*
4,1,15,-.00398,.00044,
-.003999,.000208,
-.004004,-.000025,
-.003996,-.000258,
-.00398,-.00044,
-.00483,-.00129,
-.004897,-.001007,
-.004947,-.000721,
-.004981,-.000432,
-.004997,-.000141,
-.004997,.000149,
-.00498,.00044,
-.004946,.000729,
-.004895,.001015,
-.00483,.00129,
-.00398,.00044,
90.*
4,1,15,-.00044,-.00398,
-.000208,-.003999,
.000025,-.004004,
.000258,-.003996,
.00044,-.00398,
.00129,-.00483,
.001007,-.004897,
.000721,-.004947,
.000432,-.004981,
.000141,-.004997,
-.000149,-.004997,
-.00044,-.00498,
-.000729,-.004946,
-.001015,-.004895,
-.00129,-.00483,
-.00044,-.00398,
90.*
4,1,15,.00398,-.00044,
.003999,-.000208,
.004004,.000025,
.003996,.000258,
.00398,.00044,
.00483,.00129,
.004897,.001007,
.004947,.000721,
.004981,.000432,
.004997,.000141,
.004997,-.000149,
.00498,-.00044,
.004946,-.000729,
.004895,-.001015,
.00483,-.00129,
.00398,-.00044,
90.*
4,1,15,.00044,.00398,
.000208,.003999,
-.000025,.004004,
-.000258,.003996,
-.00044,.00398,
-.00129,.00483,
-.001007,.004897,
-.000721,.004947,
-.000432,.004981,
-.000141,.004997,
.000149,.004997,
.00044,.00498,
.000729,.004946,
.001015,.004895,
.00129,.00483,
.00044,.00398,
90.*
%
%ADD26MACRO26*%
%AMMACRO11*
4,1,15,.00398,.00044,
.003999,.000208,
.004004,-.000025,
.003996,-.000258,
.00398,-.00044,
.00483,-.00129,
.004897,-.001007,
.004947,-.000721,
.004981,-.000432,
.004997,-.000141,
.004997,.000149,
.00498,.00044,
.004946,.000729,
.004895,.001015,
.00483,.00129,
.00398,.00044,
0.0*
4,1,15,.00044,-.00398,
.000208,-.003999,
-.000025,-.004004,
-.000258,-.003996,
-.00044,-.00398,
-.00129,-.00483,
-.001007,-.004897,
-.000721,-.004947,
-.000432,-.004981,
-.000141,-.004997,
.000149,-.004997,
.00044,-.00498,
.000729,-.004946,
.001015,-.004895,
.00129,-.00483,
.00044,-.00398,
0.0*
4,1,15,-.00398,-.00044,
-.003999,-.000208,
-.004004,.000025,
-.003996,.000258,
-.00398,.00044,
-.00483,.00129,
-.004897,.001007,
-.004947,.000721,
-.004981,.000432,
-.004997,.000141,
-.004997,-.000149,
-.00498,-.00044,
-.004946,-.000729,
-.004895,-.001015,
-.00483,-.00129,
-.00398,-.00044,
0.0*
4,1,15,-.00044,.00398,
-.000208,.003999,
.000025,.004004,
.000258,.003996,
.00044,.00398,
.00129,.00483,
.001007,.004897,
.000721,.004947,
.000432,.004981,
.000141,.004997,
-.000149,.004997,
-.00044,.00498,
-.000729,.004946,
-.001015,.004895,
-.00129,.00483,
-.00044,.00398,
0.0*
%
%ADD11MACRO11*%
%AMMACRO28*
4,1,15,-.00398,.00044,
-.003999,.000208,
-.004004,-.000025,
-.003996,-.000258,
-.00398,-.00044,
-.00483,-.00129,
-.004897,-.001007,
-.004947,-.000721,
-.004981,-.000432,
-.004997,-.000141,
-.004997,.000149,
-.00498,.00044,
-.004946,.000729,
-.004895,.001015,
-.00483,.00129,
-.00398,.00044,
0.0*
4,1,15,-.00044,-.00398,
-.000208,-.003999,
.000025,-.004004,
.000258,-.003996,
.00044,-.00398,
.00129,-.00483,
.001007,-.004897,
.000721,-.004947,
.000432,-.004981,
.000141,-.004997,
-.000149,-.004997,
-.00044,-.00498,
-.000729,-.004946,
-.001015,-.004895,
-.00129,-.00483,
-.00044,-.00398,
0.0*
4,1,15,.00398,-.00044,
.003999,-.000208,
.004004,.000025,
.003996,.000258,
.00398,.00044,
.00483,.00129,
.004897,.001007,
.004947,.000721,
.004981,.000432,
.004997,.000141,
.004997,-.000149,
.00498,-.00044,
.004946,-.000729,
.004895,-.001015,
.00483,-.00129,
.00398,-.00044,
0.0*
4,1,15,.00044,.00398,
.000208,.003999,
-.000025,.004004,
-.000258,.003996,
-.00044,.00398,
-.00129,.00483,
-.001007,.004897,
-.000721,.004947,
-.000432,.004981,
-.000141,.004997,
.000149,.004997,
.00044,.00498,
.000729,.004946,
.001015,.004895,
.00129,.00483,
.00044,.00398,
0.0*
%
%ADD28MACRO28*%
%ADD20C,.122*%
%ADD10C,.114*%
%ADD34C,.115*%
%ADD21C,.125*%
%ADD32C,.147*%
%ADD30C,.178*%
%AMMACRO19*
4,1,12,.04693,.01865,
.049456,.010217,
.050478,.001474,
.049968,-.007314,
.047938,-.015879,
.04693,-.01865,
.05075,-.02247,
.053881,-.013316,
.055375,-.003757,
.055186,.005915,
.05332,.015408,
.05075,.02247,
.04693,.01865,
0.0*
4,1,12,.01865,-.04693,
.010217,-.049456,
.001474,-.050478,
-.007314,-.049968,
-.015879,-.047938,
-.01865,-.04693,
-.02247,-.05075,
-.013316,-.053881,
-.003757,-.055375,
.005915,-.055186,
.015408,-.05332,
.02247,-.05075,
.01865,-.04693,
0.0*
4,1,12,-.04693,-.01865,
-.049456,-.010217,
-.050478,-.001474,
-.049968,.007314,
-.047938,.015879,
-.04693,.01865,
-.05075,.02247,
-.053881,.013316,
-.055375,.003757,
-.055186,-.005915,
-.05332,-.015408,
-.05075,-.02247,
-.04693,-.01865,
0.0*
4,1,12,-.01865,.04693,
-.010217,.049456,
-.001474,.050478,
.007314,.049968,
.015879,.047938,
.01865,.04693,
.02247,.05075,
.013316,.053881,
.003757,.055375,
-.005915,.055186,
-.015408,.05332,
-.02247,.05075,
-.01865,.04693,
0.0*
%
%ADD19MACRO19*%
%AMMACRO35*
4,1,15,.00398,.00044,
.003999,.000208,
.004004,-.000025,
.003996,-.000258,
.00398,-.00044,
.00483,-.00129,
.004897,-.001007,
.004947,-.000721,
.004981,-.000432,
.004997,-.000141,
.004997,.000149,
.00498,.00044,
.004946,.000729,
.004895,.001015,
.00483,.00129,
.00398,.00044,
225.*
4,1,15,.00044,-.00398,
.000208,-.003999,
-.000025,-.004004,
-.000258,-.003996,
-.00044,-.00398,
-.00129,-.00483,
-.001007,-.004897,
-.000721,-.004947,
-.000432,-.004981,
-.000141,-.004997,
.000149,-.004997,
.00044,-.00498,
.000729,-.004946,
.001015,-.004895,
.00129,-.00483,
.00044,-.00398,
225.*
4,1,15,-.00398,-.00044,
-.003999,-.000208,
-.004004,.000025,
-.003996,.000258,
-.00398,.00044,
-.00483,.00129,
-.004897,.001007,
-.004947,.000721,
-.004981,.000432,
-.004997,.000141,
-.004997,-.000149,
-.00498,-.00044,
-.004946,-.000729,
-.004895,-.001015,
-.00483,-.00129,
-.00398,-.00044,
225.*
4,1,15,-.00044,.00398,
-.000208,.003999,
.000025,.004004,
.000258,.003996,
.00044,.00398,
.00129,.00483,
.001007,.004897,
.000721,.004947,
.000432,.004981,
.000141,.004997,
-.000149,.004997,
-.00044,.00498,
-.000729,.004946,
-.001015,.004895,
-.00129,.00483,
-.00044,.00398,
225.*
%
%ADD35MACRO35*%
%AMMACRO13*
4,1,15,.00398,.00044,
.003999,.000208,
.004004,-.000025,
.003996,-.000258,
.00398,-.00044,
.00483,-.00129,
.004897,-.001007,
.004947,-.000721,
.004981,-.000432,
.004997,-.000141,
.004997,.000149,
.00498,.00044,
.004946,.000729,
.004895,.001015,
.00483,.00129,
.00398,.00044,
180.*
4,1,15,.00044,-.00398,
.000208,-.003999,
-.000025,-.004004,
-.000258,-.003996,
-.00044,-.00398,
-.00129,-.00483,
-.001007,-.004897,
-.000721,-.004947,
-.000432,-.004981,
-.000141,-.004997,
.000149,-.004997,
.00044,-.00498,
.000729,-.004946,
.001015,-.004895,
.00129,-.00483,
.00044,-.00398,
180.*
4,1,15,-.00398,-.00044,
-.003999,-.000208,
-.004004,.000025,
-.003996,.000258,
-.00398,.00044,
-.00483,.00129,
-.004897,.001007,
-.004947,.000721,
-.004981,.000432,
-.004997,.000141,
-.004997,-.000149,
-.00498,-.00044,
-.004946,-.000729,
-.004895,-.001015,
-.00483,-.00129,
-.00398,-.00044,
180.*
4,1,15,-.00044,.00398,
-.000208,.003999,
.000025,.004004,
.000258,.003996,
.00044,.00398,
.00129,.00483,
.001007,.004897,
.000721,.004947,
.000432,.004981,
.000141,.004997,
-.000149,.004997,
-.00044,.00498,
-.000729,.004946,
-.001015,.004895,
-.00129,.00483,
-.00044,.00398,
180.*
%
%ADD13MACRO13*%
%AMMACRO12*
4,1,15,.00398,.00044,
.003999,.000208,
.004004,-.000025,
.003996,-.000258,
.00398,-.00044,
.00483,-.00129,
.004897,-.001007,
.004947,-.000721,
.004981,-.000432,
.004997,-.000141,
.004997,.000149,
.00498,.00044,
.004946,.000729,
.004895,.001015,
.00483,.00129,
.00398,.00044,
270.*
4,1,15,.00044,-.00398,
.000208,-.003999,
-.000025,-.004004,
-.000258,-.003996,
-.00044,-.00398,
-.00129,-.00483,
-.001007,-.004897,
-.000721,-.004947,
-.000432,-.004981,
-.000141,-.004997,
.000149,-.004997,
.00044,-.00498,
.000729,-.004946,
.001015,-.004895,
.00129,-.00483,
.00044,-.00398,
270.*
4,1,15,-.00398,-.00044,
-.003999,-.000208,
-.004004,.000025,
-.003996,.000258,
-.00398,.00044,
-.00483,.00129,
-.004897,.001007,
-.004947,.000721,
-.004981,.000432,
-.004997,.000141,
-.004997,-.000149,
-.00498,-.00044,
-.004946,-.000729,
-.004895,-.001015,
-.00483,-.00129,
-.00398,-.00044,
270.*
4,1,15,-.00044,.00398,
-.000208,.003999,
.000025,.004004,
.000258,.003996,
.00044,.00398,
.00129,.00483,
.001007,.004897,
.000721,.004947,
.000432,.004981,
.000141,.004997,
-.000149,.004997,
-.00044,.00498,
-.000729,.004946,
-.001015,.004895,
-.00129,.00483,
-.00044,.00398,
270.*
%
%ADD12MACRO12*%
%AMMACRO36*
4,1,15,-.00398,.00044,
-.003999,.000208,
-.004004,-.000025,
-.003996,-.000258,
-.00398,-.00044,
-.00483,-.00129,
-.004897,-.001007,
-.004947,-.000721,
-.004981,-.000432,
-.004997,-.000141,
-.004997,.000149,
-.00498,.00044,
-.004946,.000729,
-.004895,.001015,
-.00483,.00129,
-.00398,.00044,
135.*
4,1,15,-.00044,-.00398,
-.000208,-.003999,
.000025,-.004004,
.000258,-.003996,
.00044,-.00398,
.00129,-.00483,
.001007,-.004897,
.000721,-.004947,
.000432,-.004981,
.000141,-.004997,
-.000149,-.004997,
-.00044,-.00498,
-.000729,-.004946,
-.001015,-.004895,
-.00129,-.00483,
-.00044,-.00398,
135.*
4,1,15,.00398,-.00044,
.003999,-.000208,
.004004,.000025,
.003996,.000258,
.00398,.00044,
.00483,.00129,
.004897,.001007,
.004947,.000721,
.004981,.000432,
.004997,.000141,
.004997,-.000149,
.00498,-.00044,
.004946,-.000729,
.004895,-.001015,
.00483,-.00129,
.00398,-.00044,
135.*
4,1,15,.00044,.00398,
.000208,.003999,
-.000025,.004004,
-.000258,.003996,
-.00044,.00398,
-.00129,.00483,
-.001007,.004897,
-.000721,.004947,
-.000432,.004981,
-.000141,.004997,
.000149,.004997,
.00044,.00498,
.000729,.004946,
.001015,.004895,
.00129,.00483,
.00044,.00398,
135.*
%
%ADD36MACRO36*%
%AMMACRO29*
4,1,15,-.00398,.00044,
-.003999,.000208,
-.004004,-.000025,
-.003996,-.000258,
-.00398,-.00044,
-.00483,-.00129,
-.004897,-.001007,
-.004947,-.000721,
-.004981,-.000432,
-.004997,-.000141,
-.004997,.000149,
-.00498,.00044,
-.004946,.000729,
-.004895,.001015,
-.00483,.00129,
-.00398,.00044,
270.*
4,1,15,-.00044,-.00398,
-.000208,-.003999,
.000025,-.004004,
.000258,-.003996,
.00044,-.00398,
.00129,-.00483,
.001007,-.004897,
.000721,-.004947,
.000432,-.004981,
.000141,-.004997,
-.000149,-.004997,
-.00044,-.00498,
-.000729,-.004946,
-.001015,-.004895,
-.00129,-.00483,
-.00044,-.00398,
270.*
4,1,15,.00398,-.00044,
.003999,-.000208,
.004004,.000025,
.003996,.000258,
.00398,.00044,
.00483,.00129,
.004897,.001007,
.004947,.000721,
.004981,.000432,
.004997,.000141,
.004997,-.000149,
.00498,-.00044,
.004946,-.000729,
.004895,-.001015,
.00483,-.00129,
.00398,-.00044,
270.*
4,1,15,.00044,.00398,
.000208,.003999,
-.000025,.004004,
-.000258,.003996,
-.00044,.00398,
-.00129,.00483,
-.001007,.004897,
-.000721,.004947,
-.000432,.004981,
-.000141,.004997,
.000149,.004997,
.00044,.00498,
.000729,.004946,
.001015,.004895,
.00129,.00483,
.00044,.00398,
270.*
%
%ADD29MACRO29*%
%AMMACRO27*
4,1,15,-.00398,.00044,
-.003999,.000208,
-.004004,-.000025,
-.003996,-.000258,
-.00398,-.00044,
-.00483,-.00129,
-.004897,-.001007,
-.004947,-.000721,
-.004981,-.000432,
-.004997,-.000141,
-.004997,.000149,
-.00498,.00044,
-.004946,.000729,
-.004895,.001015,
-.00483,.00129,
-.00398,.00044,
180.*
4,1,15,-.00044,-.00398,
-.000208,-.003999,
.000025,-.004004,
.000258,-.003996,
.00044,-.00398,
.00129,-.00483,
.001007,-.004897,
.000721,-.004947,
.000432,-.004981,
.000141,-.004997,
-.000149,-.004997,
-.00044,-.00498,
-.000729,-.004946,
-.001015,-.004895,
-.00129,-.00483,
-.00044,-.00398,
180.*
4,1,15,.00398,-.00044,
.003999,-.000208,
.004004,.000025,
.003996,.000258,
.00398,.00044,
.00483,.00129,
.004897,.001007,
.004947,.000721,
.004981,.000432,
.004997,.000141,
.004997,-.000149,
.00498,-.00044,
.004946,-.000729,
.004895,-.001015,
.00483,-.00129,
.00398,-.00044,
180.*
4,1,15,.00044,.00398,
.000208,.003999,
-.000025,.004004,
-.000258,.003996,
-.00044,.00398,
-.00129,.00483,
-.001007,.004897,
-.000721,.004947,
-.000432,.004981,
-.000141,.004997,
.000149,.004997,
.00044,.00498,
.000729,.004946,
.001015,.004895,
.00129,.00483,
.00044,.00398,
180.*
%
%ADD27MACRO27*%
%AMMACRO37*
4,1,15,.00398,.00044,
.003999,.000208,
.004004,-.000025,
.003996,-.000258,
.00398,-.00044,
.00483,-.00129,
.004897,-.001007,
.004947,-.000721,
.004981,-.000432,
.004997,-.000141,
.004997,.000149,
.00498,.00044,
.004946,.000729,
.004895,.001015,
.00483,.00129,
.00398,.00044,
282.*
4,1,15,.00044,-.00398,
.000208,-.003999,
-.000025,-.004004,
-.000258,-.003996,
-.00044,-.00398,
-.00129,-.00483,
-.001007,-.004897,
-.000721,-.004947,
-.000432,-.004981,
-.000141,-.004997,
.000149,-.004997,
.00044,-.00498,
.000729,-.004946,
.001015,-.004895,
.00129,-.00483,
.00044,-.00398,
282.*
4,1,15,-.00398,-.00044,
-.003999,-.000208,
-.004004,.000025,
-.003996,.000258,
-.00398,.00044,
-.00483,.00129,
-.004897,.001007,
-.004947,.000721,
-.004981,.000432,
-.004997,.000141,
-.004997,-.000149,
-.00498,-.00044,
-.004946,-.000729,
-.004895,-.001015,
-.00483,-.00129,
-.00398,-.00044,
282.*
4,1,15,-.00044,.00398,
-.000208,.003999,
.000025,.004004,
.000258,.003996,
.00044,.00398,
.00129,.00483,
.001007,.004897,
.000721,.004947,
.000432,.004981,
.000141,.004997,
-.000149,.004997,
-.00044,.00498,
-.000729,.004946,
-.001015,.004895,
-.00129,.00483,
-.00044,.00398,
282.*
%
%ADD37MACRO37*%
%AMMACRO18*
4,1,13,.03683,.01561,
.038981,.008977,
.039948,.002072,
.039701,-.004896,
.038247,-.011716,
.03683,-.01561,
.04061,-.01939,
.04336,-.012044,
.044793,-.004331,
.044864,.003513,
.043573,.01125,
.040957,.018645,
.04061,.01939,
.03683,.01561,
0.0*
4,1,13,.01561,-.03683,
.008977,-.038981,
.002072,-.039948,
-.004896,-.039701,
-.011716,-.038247,
-.01561,-.03683,
-.01939,-.04061,
-.012044,-.04336,
-.004331,-.044793,
.003513,-.044864,
.01125,-.043573,
.018645,-.040957,
.01939,-.04061,
.01561,-.03683,
0.0*
4,1,13,-.03683,-.01561,
-.038981,-.008977,
-.039948,-.002072,
-.039701,.004896,
-.038247,.011716,
-.03683,.01561,
-.04061,.01939,
-.04336,.012044,
-.044793,.004331,
-.044864,-.003513,
-.043573,-.01125,
-.040957,-.018645,
-.04061,-.01939,
-.03683,-.01561,
0.0*
4,1,13,-.01561,.03683,
-.008977,.038981,
-.002072,.039948,
.004896,.039701,
.011716,.038247,
.01561,.03683,
.01939,.04061,
.012044,.04336,
.004331,.044793,
-.003513,.044864,
-.01125,.043573,
-.018645,.040957,
-.01939,.04061,
-.01561,.03683,
0.0*
%
%ADD18MACRO18*%
%ADD38C,.02*%
%ADD39C,.006*%
%ADD46C,.06604*%
%ADD41C,.11004*%
%ADD44C,.11104*%
%ADD47C,.11804*%
%ADD45C,.37405*%
%ADD40C,.23626*%
%ADD43C,.37406*%
%ADD42C,.23627*%
%ADD48C,.27563*%
G75*
%LPD*%
G75*
G36*
G01X-6000Y-6000D02*
X832772D01*
Y576866D01*
X-6000D01*
Y-6000D01*
G37*
%LPC*%
G75*
G36*
G01X326783Y567862D02*
G02X331652Y562992I-1J-4870D01*
G01Y520719D01*
G03X350756Y498316I22689J1D01*
G01X383620Y493059D01*
X443151D01*
X476035Y498319D01*
G03X495140Y520723I-3584J22404D01*
G01Y562992D01*
G02X500010Y567862I4870J0D01*
G01X818898D01*
G02X823768Y562992I0J-4870D01*
G01Y7874D01*
G02X818898Y3004I-4870J0D01*
G01X7874D01*
G02X3004Y7874I0J4870D01*
G01Y562992D01*
G02X7874Y567862I4870J0D01*
G01X326783D01*
G37*
%LPD*%
G75*
G36*
G01X655786Y118047D02*
X657478D01*
G02X657479Y115025I1J-1511D01*
G01X654331Y115024D01*
G02X653474Y117780I0J1511D01*
G03Y118440I-227J330D01*
G02X652818Y119685I855J1246D01*
G01Y122834D01*
G02X653474Y124080I1511J0D01*
G03Y124739I-227J330D01*
G02Y127229I857J1245D01*
G03Y127888I-227J330D01*
G02X652818Y129134I855J1246D01*
G01Y132283D01*
G02X653179Y133262I1512J-1D01*
G03X652874Y133922I-305J260D01*
G01X651180D01*
G02X651181Y136944I1J1511D01*
G01X652873D01*
G03X653178Y137603I0J400D01*
G02X652818Y138582I1151J979D01*
G01Y141732D01*
G02X653179Y142711I1512J-1D01*
G03X652874Y143370I-305J259D01*
G01X651180D01*
G02X651181Y146394I1J1512D01*
G01X652873D01*
G03X653178Y147052I0J400D01*
G02X652818Y148031I1151J979D01*
G01Y151181D01*
G02X655842I1512J0D01*
G01Y148030D01*
G02X655187Y146786I-1512J1D01*
G03Y146127I227J-329D01*
G02X655186Y143637I-857J-1245D01*
G03Y142977I227J-330D01*
G02X655842Y141732I-855J-1246D01*
G01Y138581D01*
G02X655187Y137337I-1512J1D01*
G03Y136678I227J-329D01*
G02X655186Y134188I-857J-1245D01*
G03Y133528I227J-330D01*
G02X655842Y132283I-855J-1246D01*
G01Y129133D01*
G02X655481Y128155I-1512J2D01*
G03X655786Y127496I305J-259D01*
G01X657481D01*
G02X657480Y124472I-1J-1512D01*
G01X655786D01*
G03X655481Y123813I0J-400D01*
G02X655842Y122834I-1151J-980D01*
G01Y119684D01*
G02X655482Y118706I-1512J1D01*
G03X655786Y118047I305J-259D01*
G37*
G36*
G01X661856Y118988D02*
G02X659217Y119686I-1227J697D01*
G01X659218D01*
Y122833D01*
G02X661857Y123532I1412J1D01*
G03X662552I347J198D01*
G02X665190Y122834I1227J-698D01*
G01Y119685D01*
G02X662552Y118988I-1411J0D01*
G03X661856I-348J-198D01*
G37*
G36*
G01X671305D02*
G02X668666Y119686I-1227J697D01*
G01X668667D01*
Y122834D01*
G02X671306Y123532I1412J1D01*
G03X672002I348J198D01*
G02X674641Y122834I1227J-697D01*
G01X674640D01*
Y119685D01*
X674639D01*
G02X672001Y118988I-1411J0D01*
G03X671305I-348J-198D01*
G37*
G36*
G01X680754D02*
G02X678115Y119686I-1227J697D01*
G01X678116D01*
Y122834D01*
G02X680755Y123532I1412J1D01*
G03X681451I348J198D01*
G02X684090Y122834I1227J-697D01*
G01X684089D01*
Y119685D01*
X684088D01*
G02X681450Y118988I-1411J0D01*
G03X680754I-348J-198D01*
G37*
G36*
G01X690203D02*
G02X687564Y119686I-1227J697D01*
G01X687565D01*
Y122834D01*
G02X690204Y123533I1412J1D01*
G03X690899I347J198D01*
G02X693538Y122835I1227J-698D01*
G01Y119686D01*
G02X690899Y118988I-1412J0D01*
G03X690203I-348J-197D01*
G37*
G36*
G01X406672Y412981D02*
X406676Y412940D01*
X408791Y408991D01*
X408823Y408966D01*
G02X405336Y407098I-1343J-1682D01*
G01X405332Y407139D01*
X403218Y411087D01*
X403186Y411113D01*
G02X406672Y412981I1342J1682D01*
G37*
G36*
G01X414195Y407097D02*
X414192Y407138D01*
X412075Y411088D01*
X412043Y411113D01*
G02X415530Y412982I1343J1682D01*
G01X415533Y412941D01*
X417650Y408991D01*
X417682Y408965D01*
G02X414195Y407097I-1343J-1681D01*
G37*
G36*
G01X406672Y427942D02*
X406676Y427901D01*
X408791Y423951D01*
X408823Y423926D01*
G02X405336Y422058I-1343J-1682D01*
G01X405332Y422099D01*
X403218Y426048D01*
X403186Y426074D01*
G02X406672Y427942I1342J1682D01*
G37*
G36*
G01X414195Y422057D02*
X414192Y422098D01*
X412076Y426048D01*
X412044Y426074D01*
G02X415530Y427943I1342J1682D01*
G01X415533Y427902D01*
X417650Y423951D01*
X417682Y423925D01*
G02X414195Y422057I-1343J-1681D01*
G37*
G36*
G01X390400Y38583D02*
G02X385978I-2211J0D01*
G01Y44096D01*
G02X390400Y44095I2211J-1D01*
G01Y38583D01*
G37*
G36*
G01X383314Y43307D02*
G02X378892I-2211J0D01*
G01Y48820D01*
G02X383314Y48819I2211J-1D01*
G01Y43307D01*
G37*
G36*
G01X376228Y38583D02*
G02X371804I-2212J0D01*
G01Y44096D01*
G02X376228Y44095I2212J-1D01*
G01Y38583D01*
G37*
G36*
G01X369140Y43307D02*
G02X364718I-2211J0D01*
G01Y48820D01*
G02X369140Y48819I2211J-1D01*
G01Y43307D01*
G37*
G36*
G01X362054Y38583D02*
G02X357632I-2211J0D01*
G01Y44096D01*
G02X362054Y44095I2211J-1D01*
G01Y38583D01*
G37*
G36*
G01X354968Y43307D02*
G02X350544I-2212J0D01*
G01Y48820D01*
G02X354968Y48819I2212J-1D01*
G01Y43307D01*
G37*
G36*
G01X347882Y38583D02*
G02X343458I-2212J0D01*
G01Y44096D01*
G02X347882Y44095I2212J-1D01*
G01Y38583D01*
G37*
G36*
G01X340794Y43307D02*
G02X336372I-2211J0D01*
G01Y48820D01*
G02X340794Y48819I2211J-1D01*
G01Y43307D01*
G37*
G36*
G01Y14961D02*
G02X336372I-2211J0D01*
G01Y20474D01*
G02X340794Y20473I2211J-1D01*
G01Y14961D01*
G37*
G36*
G01X347882Y10237D02*
G02X343458I-2212J0D01*
G01Y15749D01*
G02X347882Y15748I2212J-1D01*
G01Y10237D01*
G37*
G36*
G01X354968Y14961D02*
G02X350544I-2212J0D01*
G01Y20474D01*
G02X354968Y20473I2212J-1D01*
G01Y14961D01*
G37*
G36*
G01X362054Y10237D02*
G02X357632I-2211J0D01*
G01Y15749D01*
G02X362054Y15748I2211J-1D01*
G01Y10237D01*
G37*
G36*
G01X369140Y14961D02*
G02X364718I-2211J0D01*
G01Y20474D01*
G02X369140Y20473I2211J-1D01*
G01Y14961D01*
G37*
G36*
G01X376228Y10237D02*
G02X371804I-2212J0D01*
G01Y15749D01*
G02X376228Y15748I2212J-1D01*
G01Y10237D01*
G37*
G36*
G01X383314Y14961D02*
G02X378892I-2211J0D01*
G01Y20474D01*
G02X383314Y20473I2211J-1D01*
G01Y14961D01*
G37*
G36*
G01X390400Y10237D02*
G02X385978I-2211J0D01*
G01Y15749D01*
G02X390400Y15748I2211J-1D01*
G01Y10237D01*
G37*
G36*
G01X380100Y172298D02*
G02X379898Y172500I0J202D01*
G01Y175700D01*
G02X380100Y175902I202J0D01*
G01X380900D01*
G02X381102Y175700I0J-202D01*
G01Y172500D01*
G02X380900Y172298I-202J0D01*
G01X380100D01*
G37*
G36*
G01X382300D02*
G02X382098Y172500I0J202D01*
G01Y175700D01*
G02X382300Y175902I202J0D01*
G01X383100D01*
G02X383302Y175700I0J-202D01*
G01Y172500D01*
G02X383100Y172298I-202J0D01*
G01X382300D01*
G37*
G36*
G01X386100D02*
G02X385898Y172500I0J202D01*
G01Y175700D01*
G02X386100Y175902I202J0D01*
G01X386900D01*
G02X387102Y175700I0J-202D01*
G01Y172500D01*
G02X386900Y172298I-202J0D01*
G01X386100D01*
G37*
G36*
G01X388300D02*
G02X388098Y172500I0J202D01*
G01Y175700D01*
G02X388300Y175902I202J0D01*
G01X389100D01*
G02X389302Y175700I0J-202D01*
G01Y172500D01*
G02X389100Y172298I-202J0D01*
G01X388300D01*
G37*
G36*
G01X378311Y216490D02*
G02X378110Y216692I1J202D01*
G01Y217492D01*
G02X378311Y217694I201J1D01*
G01X381511D01*
G02X381712Y217492I-1J-202D01*
G01Y216692D01*
G02X381511Y216490I-201J-1D01*
G01X378311D01*
G37*
G36*
G01Y214190D02*
G02X378110Y214392I1J202D01*
G01Y215192D01*
G02X378311Y215394I201J1D01*
G01X381511D01*
G02X381712Y215192I-1J-202D01*
G01Y214392D01*
G02X381511Y214190I-201J-1D01*
G01X378311D01*
G37*
G36*
G01Y210990D02*
G02X378110Y211192I1J202D01*
G01Y211992D01*
G02X378311Y212194I201J1D01*
G01X381511D01*
G02X381712Y211992I-1J-202D01*
G01Y211192D01*
G02X381511Y210990I-201J-1D01*
G01X378311D01*
G37*
G36*
G01Y208690D02*
G02X378110Y208892I1J202D01*
G01Y209692D01*
G02X378311Y209894I201J1D01*
G01X381511D01*
G02X381712Y209692I-1J-202D01*
G01Y208892D01*
G02X381511Y208690I-201J-1D01*
G01X378311D01*
G37*
G36*
G01Y205490D02*
G02X378110Y205692I1J202D01*
G01Y206492D01*
G02X378311Y206694I201J1D01*
G01X381511D01*
G02X381712Y206492I-1J-202D01*
G01Y205692D01*
G02X381511Y205490I-201J-1D01*
G01X378311D01*
G37*
G36*
G01Y203190D02*
G02X378110Y203392I1J202D01*
G01Y204192D01*
G02X378311Y204394I201J1D01*
G01X381511D01*
G02X381712Y204192I-1J-202D01*
G01Y203392D01*
G02X381511Y203190I-201J-1D01*
G01X378311D01*
G37*
G36*
G01Y199990D02*
G02X378110Y200192I1J202D01*
G01Y200992D01*
G02X378311Y201194I201J1D01*
G01X381511D01*
G02X381712Y200992I-1J-202D01*
G01Y200192D01*
G02X381511Y199990I-201J-1D01*
G01X378311D01*
G37*
G36*
G01Y197690D02*
G02X378110Y197892I1J202D01*
G01Y198692D01*
G02X378311Y198894I201J1D01*
G01X381511D01*
G02X381712Y198692I-1J-202D01*
G01Y197892D01*
G02X381511Y197690I-201J-1D01*
G01X378311D01*
G37*
G36*
G01X391176Y212599D02*
G02X388352I-1412J0D01*
G01Y216537D01*
G02X391176Y216536I1412J-1D01*
G01Y212599D01*
G37*
G36*
G01X454180Y43307D02*
G02X449758I-2211J0D01*
G01Y48820D01*
G02X454180Y48819I2211J-1D01*
G01Y43307D01*
G37*
G36*
G01X447094Y38583D02*
G02X442670I-2212J0D01*
G01Y44096D01*
G02X447094Y44095I2212J-1D01*
G01Y38583D01*
G37*
G36*
G01X440008Y43307D02*
G02X435584I-2212J0D01*
G01Y48820D01*
G02X440008Y48819I2212J-1D01*
G01Y43307D01*
G37*
G36*
G01X432920Y38583D02*
G02X428498I-2211J0D01*
G01Y44096D01*
G02X432920Y44095I2211J-1D01*
G01Y38583D01*
G37*
G36*
G01X425834Y43307D02*
G02X421410I-2212J0D01*
G01Y48820D01*
G02X425834Y48819I2212J-1D01*
G01Y43307D01*
G37*
G36*
G01X418748Y38583D02*
G02X414324I-2212J0D01*
G01Y44096D01*
G02X418748Y44095I2212J-1D01*
G01Y38583D01*
G37*
G36*
G01X411660Y43307D02*
G02X407238I-2211J0D01*
G01Y48820D01*
G02X411660Y48819I2211J-1D01*
G01Y43307D01*
G37*
G36*
G01X404574Y38583D02*
G02X400152I-2211J0D01*
G01Y44096D01*
G02X404574Y44095I2211J-1D01*
G01Y38583D01*
G37*
G36*
G01X397488Y43307D02*
G02X393064I-2212J0D01*
G01Y48820D01*
G02X397488Y48819I2212J-1D01*
G01Y43307D01*
G37*
G36*
G01Y14961D02*
G02X393064I-2212J0D01*
G01Y20474D01*
G02X397488Y20473I2212J-1D01*
G01Y14961D01*
G37*
G36*
G01X404574Y10237D02*
G02X400152I-2211J0D01*
G01Y15749D01*
G02X404574Y15748I2211J-1D01*
G01Y10237D01*
G37*
G36*
G01X411660Y14961D02*
G02X407238I-2211J0D01*
G01Y20474D01*
G02X411660Y20473I2211J-1D01*
G01Y14961D01*
G37*
G36*
G01X418748Y10237D02*
G02X414324I-2212J0D01*
G01Y15749D01*
G02X418748Y15748I2212J-1D01*
G01Y10237D01*
G37*
G36*
G01X425834Y14961D02*
G02X421410I-2212J0D01*
G01Y20474D01*
G02X425834Y20473I2212J-1D01*
G01Y14961D01*
G37*
G36*
G01X432920Y10237D02*
G02X428498I-2211J0D01*
G01Y15749D01*
G02X432920Y15748I2211J-1D01*
G01Y10237D01*
G37*
G36*
G01X440008Y14961D02*
G02X435584I-2212J0D01*
G01Y20474D01*
G02X440008Y20473I2212J-1D01*
G01Y14961D01*
G37*
G36*
G01X447094Y10237D02*
G02X442670I-2212J0D01*
G01Y15749D01*
G02X447094Y15748I2212J-1D01*
G01Y10237D01*
G37*
G36*
G01X454180Y14961D02*
G02X449758I-2211J0D01*
G01Y20474D01*
G02X454180Y20473I2211J-1D01*
G01Y14961D01*
G37*
G36*
G01X392100Y172298D02*
G02X391898Y172500I0J202D01*
G01Y175700D01*
G02X392100Y175902I202J0D01*
G01X392900D01*
G02X393102Y175700I0J-202D01*
G01Y172500D01*
G02X392900Y172298I-202J0D01*
G01X392100D01*
G37*
G36*
G01X394300D02*
G02X394098Y172500I0J202D01*
G01Y175700D01*
G02X394300Y175902I202J0D01*
G01X395100D01*
G02X395302Y175700I0J-202D01*
G01Y172500D01*
G02X395100Y172298I-202J0D01*
G01X394300D01*
G37*
G36*
G01X398100D02*
G02X397898Y172500I0J202D01*
G01Y175700D01*
G02X398100Y175902I202J0D01*
G01X398900D01*
G02X399102Y175700I0J-202D01*
G01Y172500D01*
G02X398900Y172298I-202J0D01*
G01X398100D01*
G37*
G36*
G01X400300D02*
G02X400098Y172500I0J202D01*
G01Y175700D01*
G02X400300Y175902I202J0D01*
G01X401100D01*
G02X401302Y175700I0J-202D01*
G01Y172500D01*
G02X401100Y172298I-202J0D01*
G01X400300D01*
G37*
G36*
G01X404100D02*
G02X403898Y172500I0J202D01*
G01Y175700D01*
G02X404100Y175902I202J0D01*
G01X404900D01*
G02X405102Y175700I0J-202D01*
G01Y172500D01*
G02X404900Y172298I-202J0D01*
G01X404100D01*
G37*
G36*
G01X406300D02*
G02X406098Y172500I0J202D01*
G01Y175700D01*
G02X406300Y175902I202J0D01*
G01X407100D01*
G02X407302Y175700I0J-202D01*
G01Y172500D01*
G02X407100Y172298I-202J0D01*
G01X406300D01*
G37*
G36*
G01X410100D02*
G02X409898Y172500I0J202D01*
G01Y175700D01*
G02X410100Y175902I202J0D01*
G01X410900D01*
G02X411102Y175700I0J-202D01*
G01Y172500D01*
G02X410900Y172298I-202J0D01*
G01X410100D01*
G37*
G36*
G01X412300D02*
G02X412098Y172500I0J202D01*
G01Y175700D01*
G02X412300Y175902I202J0D01*
G01X413100D01*
G02X413302Y175700I0J-202D01*
G01Y172500D01*
G02X413100Y172298I-202J0D01*
G01X412300D01*
G37*
G36*
G01X416100D02*
G02X415898Y172500I0J202D01*
G01Y175700D01*
G02X416100Y175902I202J0D01*
G01X416900D01*
G02X417102Y175700I0J-202D01*
G01Y172500D01*
G02X416900Y172298I-202J0D01*
G01X416100D01*
G37*
G36*
G01X418300D02*
G02X418098Y172500I0J202D01*
G01Y175700D01*
G02X418300Y175902I202J0D01*
G01X419100D01*
G02X419302Y175700I0J-202D01*
G01Y172500D01*
G02X419100Y172298I-202J0D01*
G01X418300D01*
G37*
G36*
G01X422100D02*
G02X421898Y172500I0J202D01*
G01Y175700D01*
G02X422100Y175902I202J0D01*
G01X422900D01*
G02X423102Y175700I0J-202D01*
G01Y172500D01*
G02X422900Y172298I-202J0D01*
G01X422100D01*
G37*
G36*
G01X424300D02*
G02X424098Y172500I0J202D01*
G01Y175700D01*
G02X424300Y175902I202J0D01*
G01X425100D01*
G02X425302Y175700I0J-202D01*
G01Y172500D01*
G02X425100Y172298I-202J0D01*
G01X424300D01*
G37*
G36*
G01X428100D02*
G02X427898Y172500I0J202D01*
G01Y175700D01*
G02X428100Y175902I202J0D01*
G01X428900D01*
G02X429102Y175700I0J-202D01*
G01Y172500D01*
G02X428900Y172298I-202J0D01*
G01X428100D01*
G37*
G36*
G01X430300D02*
G02X430098Y172500I0J202D01*
G01Y175700D01*
G02X430300Y175902I202J0D01*
G01X431100D01*
G02X431302Y175700I0J-202D01*
G01Y172500D01*
G02X431100Y172298I-202J0D01*
G01X430300D01*
G37*
G36*
G01X434100D02*
G02X433898Y172500I0J202D01*
G01Y175700D01*
G02X434100Y175902I202J0D01*
G01X434900D01*
G02X435102Y175700I0J-202D01*
G01Y172500D01*
G02X434900Y172298I-202J0D01*
G01X434100D01*
G37*
G36*
G01X436300D02*
G02X436098Y172500I0J202D01*
G01Y175700D01*
G02X436300Y175902I202J0D01*
G01X437100D01*
G02X437302Y175700I0J-202D01*
G01Y172500D01*
G02X437100Y172298I-202J0D01*
G01X436300D01*
G37*
G36*
G01X440100D02*
G02X439898Y172500I0J202D01*
G01Y175700D01*
G02X440100Y175902I202J0D01*
G01X440900D01*
G02X441102Y175700I0J-202D01*
G01Y172500D01*
G02X440900Y172298I-202J0D01*
G01X440100D01*
G37*
G36*
G01X442300D02*
G02X442098Y172500I0J202D01*
G01Y175700D01*
G02X442300Y175902I202J0D01*
G01X443100D01*
G02X443302Y175700I0J-202D01*
G01Y172500D01*
G02X443100Y172298I-202J0D01*
G01X442300D01*
G37*
G36*
G01X446100D02*
G02X445898Y172500I0J202D01*
G01Y175700D01*
G02X446100Y175902I202J0D01*
G01X446900D01*
G02X447102Y175700I0J-202D01*
G01Y172500D01*
G02X446900Y172298I-202J0D01*
G01X446100D01*
G37*
G36*
G01X448300D02*
G02X448098Y172500I0J202D01*
G01Y175700D01*
G02X448300Y175902I202J0D01*
G01X449100D01*
G02X449302Y175700I0J-202D01*
G01Y172500D01*
G02X449100Y172298I-202J0D01*
G01X448300D01*
G37*
G36*
G01X395112Y200788D02*
G02X392290I-1411J0D01*
G01Y204726D01*
G02X395112Y204725I1411J-1D01*
G01Y200788D01*
G37*
G36*
G01X399050Y204725D02*
G02X396226I-1412J0D01*
G01Y208663D01*
G02X399050Y208662I1412J-1D01*
G01Y204725D01*
G37*
G36*
G01X406924D02*
G02X404100I-1412J0D01*
G01Y208663D01*
G02X406924Y208662I1412J-1D01*
G01Y204725D01*
G37*
G36*
G01X414798D02*
G02X411974I-1412J0D01*
G01Y208663D01*
G02X414798Y208662I1412J-1D01*
G01Y204725D01*
G37*
G36*
G01X422672D02*
G02X419848I-1412J0D01*
G01Y208663D01*
G02X422672Y208662I1412J-1D01*
G01Y204725D01*
G37*
G36*
G01X430546D02*
G02X427722I-1412J0D01*
G01Y208663D01*
G02X430546Y208662I1412J-1D01*
G01Y204725D01*
G37*
G36*
G01X399050Y216536D02*
G02X396226I-1412J0D01*
G01Y220474D01*
G02X399050Y220473I1412J-1D01*
G01Y216536D01*
G37*
G36*
G01X402986D02*
G02X400164I-1411J0D01*
G01Y220474D01*
G02X402986Y220473I1411J-1D01*
G01Y216536D01*
G37*
G36*
G01X406924D02*
G02X404100I-1412J0D01*
G01Y220474D01*
G02X406924Y220473I1412J-1D01*
G01Y216536D01*
G37*
G36*
G01X410860D02*
G02X408038I-1411J0D01*
G01Y220474D01*
G02X410860Y220473I1411J-1D01*
G01Y216536D01*
G37*
G36*
G01X414798D02*
G02X411974I-1412J0D01*
G01Y220474D01*
G02X414798Y220473I1412J-1D01*
G01Y216536D01*
G37*
G36*
G01X418734D02*
G02X415912I-1411J0D01*
G01Y220474D01*
G02X418734Y220473I1411J-1D01*
G01Y216536D01*
G37*
G36*
G01X422672D02*
G02X419848I-1412J0D01*
G01Y220474D01*
G02X422672Y220473I1412J-1D01*
G01Y216536D01*
G37*
G36*
G01X426608D02*
G02X423786I-1411J0D01*
G01Y220474D01*
G02X426608Y220473I1411J-1D01*
G01Y216536D01*
G37*
G36*
G01X430546D02*
G02X427722I-1412J0D01*
G01Y220474D01*
G02X430546Y220473I1412J-1D01*
G01Y216536D01*
G37*
G36*
G01X434482D02*
G02X431660I-1411J0D01*
G01Y220474D01*
G02X434482Y220473I1411J-1D01*
G01Y216536D01*
G37*
G36*
G01X438420D02*
G02X435596I-1412J0D01*
G01Y220474D01*
G02X438420Y220473I1412J-1D01*
G01Y216536D01*
G37*
G36*
G01X442356D02*
G02X439534I-1411J0D01*
G01Y220474D01*
G02X442356Y220473I1411J-1D01*
G01Y216536D01*
G37*
G36*
G01X446294D02*
G02X443470I-1412J0D01*
G01Y220474D01*
G02X446294Y220473I1412J-1D01*
G01Y216536D01*
G37*
G36*
G01X450230D02*
G02X447408I-1411J0D01*
G01Y220474D01*
G02X450230Y220473I1411J-1D01*
G01Y216536D01*
G37*
G36*
G01Y200788D02*
G02X447408I-1411J0D01*
G01Y204726D01*
G02X450230Y204725I1411J-1D01*
G01Y200788D01*
G37*
G36*
G01X446294Y204725D02*
G02X443470I-1412J0D01*
G01Y208663D01*
G02X446294Y208662I1412J-1D01*
G01Y204725D01*
G37*
G36*
G01X442356Y200788D02*
G02X439534I-1411J0D01*
G01Y204726D01*
G02X442356Y204725I1411J-1D01*
G01Y200788D01*
G37*
G36*
G01X438420Y204725D02*
G02X435596I-1412J0D01*
G01Y208663D01*
G02X438420Y208662I1412J-1D01*
G01Y204725D01*
G37*
G36*
G01X434482Y200788D02*
G02X431660I-1411J0D01*
G01Y204726D01*
G02X434482Y204725I1411J-1D01*
G01Y200788D01*
G37*
G36*
G01X426608D02*
G02X423786I-1411J0D01*
G01Y204726D01*
G02X426608Y204725I1411J-1D01*
G01Y200788D01*
G37*
G36*
G01X418734D02*
G02X415912I-1411J0D01*
G01Y204726D01*
G02X418734Y204725I1411J-1D01*
G01Y200788D01*
G37*
G36*
G01X410860D02*
G02X408038I-1411J0D01*
G01Y204726D01*
G02X410860Y204725I1411J-1D01*
G01Y200788D01*
G37*
G36*
G01X402986D02*
G02X400164I-1411J0D01*
G01Y204726D01*
G02X402986Y204725I1411J-1D01*
G01Y200788D01*
G37*
G36*
G01X409385Y438226D02*
G02X405575Y436184I-1905J-1021D01*
G01X402621Y441698D01*
X402601Y441738D01*
G02X406433Y443738I1927J979D01*
G01X409385Y438226D01*
G37*
G36*
G01X418244D02*
G02X414434Y436184I-1905J-1021D01*
G01X411481Y441695D01*
G02X415291Y443738I1905J1022D01*
G01X418244Y438226D01*
G37*
G36*
G01X409385Y453186D02*
G02X405575Y451144I-1905J-1021D01*
G01X402621Y456658D01*
X402601Y456698D01*
G02X406433Y458698I1927J979D01*
G01X409385Y453186D01*
G37*
G36*
G01X418244D02*
G02X414434Y451144I-1905J-1021D01*
G01X411481Y456655D01*
G02X415291Y458698I1905J1022D01*
G01X418244Y453186D01*
G37*
G36*
G01X517960Y38583D02*
G02X513536I-2212J0D01*
G01Y44096D01*
G02X517960Y44095I2212J-1D01*
G01Y38583D01*
G37*
G36*
G01X510874Y43307D02*
G02X506450I-2212J0D01*
G01Y48820D01*
G02X510874Y48819I2212J-1D01*
G01Y43307D01*
G37*
G36*
G01X503786Y38583D02*
G02X499364I-2211J0D01*
G01Y44096D01*
G02X503786Y44095I2211J-1D01*
G01Y38583D01*
G37*
G36*
G01X496700Y43307D02*
G02X492278I-2211J0D01*
G01Y48820D01*
G02X496700Y48819I2211J-1D01*
G01Y43307D01*
G37*
G36*
G01X489614Y38583D02*
G02X485190I-2212J0D01*
G01Y44096D01*
G02X489614Y44095I2212J-1D01*
G01Y38583D01*
G37*
G36*
G01X482526Y43307D02*
G02X478104I-2211J0D01*
G01Y48820D01*
G02X482526Y48819I2211J-1D01*
G01Y43307D01*
G37*
G36*
G01X475440Y38583D02*
G02X471018I-2211J0D01*
G01Y44096D01*
G02X475440Y44095I2211J-1D01*
G01Y38583D01*
G37*
G36*
G01X468354Y43307D02*
G02X463930I-2212J0D01*
G01Y48820D01*
G02X468354Y48819I2212J-1D01*
G01Y43307D01*
G37*
G36*
G01X461266Y38583D02*
G02X456844I-2211J0D01*
G01Y44096D01*
G02X461266Y44095I2211J-1D01*
G01Y38583D01*
G37*
G36*
G01Y10237D02*
G02X456844I-2211J0D01*
G01Y15749D01*
G02X461266Y15748I2211J-1D01*
G01Y10237D01*
G37*
G36*
G01X468354Y14961D02*
G02X463930I-2212J0D01*
G01Y20474D01*
G02X468354Y20473I2212J-1D01*
G01Y14961D01*
G37*
G36*
G01X475440Y10237D02*
G02X471018I-2211J0D01*
G01Y15749D01*
G02X475440Y15748I2211J-1D01*
G01Y10237D01*
G37*
G36*
G01X482526Y14961D02*
G02X478104I-2211J0D01*
G01Y20474D01*
G02X482526Y20473I2211J-1D01*
G01Y14961D01*
G37*
G36*
G01X489614Y10237D02*
G02X485190I-2212J0D01*
G01Y15749D01*
G02X489614Y15748I2212J-1D01*
G01Y10237D01*
G37*
G36*
G01X496700Y14961D02*
G02X492278I-2211J0D01*
G01Y20474D01*
G02X496700Y20473I2211J-1D01*
G01Y14961D01*
G37*
G36*
G01X503786Y10237D02*
G02X499364I-2211J0D01*
G01Y15749D01*
G02X503786Y15748I2211J-1D01*
G01Y10237D01*
G37*
G36*
G01X510874Y14961D02*
G02X506450I-2212J0D01*
G01Y20474D01*
G02X510874Y20473I2212J-1D01*
G01Y14961D01*
G37*
G36*
G01X517960Y10237D02*
G02X513536I-2212J0D01*
G01Y15749D01*
G02X517960Y15748I2212J-1D01*
G01Y10237D01*
G37*
G36*
G01X452100Y172298D02*
G02X451898Y172500I0J202D01*
G01Y175700D01*
G02X452100Y175902I202J0D01*
G01X452900D01*
G02X453102Y175700I0J-202D01*
G01Y172500D01*
G02X452900Y172298I-202J0D01*
G01X452100D01*
G37*
G36*
G01X454300D02*
G02X454098Y172500I0J202D01*
G01Y175700D01*
G02X454300Y175902I202J0D01*
G01X455100D01*
G02X455302Y175700I0J-202D01*
G01Y172500D01*
G02X455100Y172298I-202J0D01*
G01X454300D01*
G37*
G36*
G01X458100D02*
G02X457898Y172500I0J202D01*
G01Y175700D01*
G02X458100Y175902I202J0D01*
G01X458900D01*
G02X459102Y175700I0J-202D01*
G01Y172500D01*
G02X458900Y172298I-202J0D01*
G01X458100D01*
G37*
G36*
G01X460300D02*
G02X460098Y172500I0J202D01*
G01Y175700D01*
G02X460300Y175902I202J0D01*
G01X461100D01*
G02X461302Y175700I0J-202D01*
G01Y172500D01*
G02X461100Y172298I-202J0D01*
G01X460300D01*
G37*
G36*
G01X464100D02*
G02X463898Y172500I0J202D01*
G01Y175700D01*
G02X464100Y175902I202J0D01*
G01X464900D01*
G02X465102Y175700I0J-202D01*
G01Y172500D01*
G02X464900Y172298I-202J0D01*
G01X464100D01*
G37*
G36*
G01X466300D02*
G02X466098Y172500I0J202D01*
G01Y175700D01*
G02X466300Y175902I202J0D01*
G01X467100D01*
G02X467302Y175700I0J-202D01*
G01Y172500D01*
G02X467100Y172298I-202J0D01*
G01X466300D01*
G37*
G36*
G01X470100D02*
G02X469898Y172500I0J202D01*
G01Y175700D01*
G02X470100Y175902I202J0D01*
G01X470900D01*
G02X471102Y175700I0J-202D01*
G01Y172500D01*
G02X470900Y172298I-202J0D01*
G01X470100D01*
G37*
G36*
G01X472300D02*
G02X472098Y172500I0J202D01*
G01Y175700D01*
G02X472300Y175902I202J0D01*
G01X473100D01*
G02X473302Y175700I0J-202D01*
G01Y172500D01*
G02X473100Y172298I-202J0D01*
G01X472300D01*
G37*
G36*
G01X477700Y153598D02*
G02X477498Y153800I0J202D01*
G01Y157000D01*
G02X477700Y157202I202J0D01*
G01X478500D01*
G02X478702Y157000I0J-202D01*
G01Y153800D01*
G02X478500Y153598I-202J0D01*
G01X477700D01*
G37*
G36*
G01X480000D02*
G02X479798Y153800I0J202D01*
G01Y157000D01*
G02X480000Y157202I202J0D01*
G01X480800D01*
G02X481002Y157000I0J-202D01*
G01Y153800D01*
G02X480800Y153598I-202J0D01*
G01X480000D01*
G37*
G36*
G01X484700D02*
G02X484498Y153800I0J202D01*
G01Y157000D01*
G02X484700Y157202I202J0D01*
G01X485500D01*
G02X485702Y157000I0J-202D01*
G01Y153800D01*
G02X485500Y153598I-202J0D01*
G01X484700D01*
G37*
G36*
G01X487000D02*
G02X486798Y153800I0J202D01*
G01Y157000D01*
G02X487000Y157202I202J0D01*
G01X487800D01*
G02X488002Y157000I0J-202D01*
G01Y153800D01*
G02X487800Y153598I-202J0D01*
G01X487000D01*
G37*
G36*
G01X491700D02*
G02X491498Y153800I0J202D01*
G01Y157000D01*
G02X491700Y157202I202J0D01*
G01X492500D01*
G02X492702Y157000I0J-202D01*
G01Y153800D01*
G02X492500Y153598I-202J0D01*
G01X491700D01*
G37*
G36*
G01X494000D02*
G02X493798Y153800I0J202D01*
G01Y157000D01*
G02X494000Y157202I202J0D01*
G01X494800D01*
G02X495002Y157000I0J-202D01*
G01Y153800D01*
G02X494800Y153598I-202J0D01*
G01X494000D01*
G37*
G36*
G01X499100D02*
G02X498898Y153800I0J202D01*
G01Y157000D01*
G02X499100Y157202I202J0D01*
G01X499900D01*
G02X500102Y157000I0J-202D01*
G01Y153800D01*
G02X499900Y153598I-202J0D01*
G01X499100D01*
G37*
G36*
G01X501400D02*
G02X501198Y153800I0J202D01*
G01Y157000D01*
G02X501400Y157202I202J0D01*
G01X502200D01*
G02X502402Y157000I0J-202D01*
G01Y153800D01*
G02X502200Y153598I-202J0D01*
G01X501400D01*
G37*
G36*
G01X504400Y159098D02*
G02X504198Y159300I0J202D01*
G01Y162500D01*
G02X504400Y162702I202J0D01*
G01X505200D01*
G02X505402Y162500I0J-202D01*
G01Y159300D01*
G02X505200Y159098I-202J0D01*
G01X504400D01*
G37*
G36*
G01X506700D02*
G02X506498Y159300I0J202D01*
G01Y162500D01*
G02X506700Y162702I202J0D01*
G01X507500D01*
G02X507702Y162500I0J-202D01*
G01Y159300D01*
G02X507500Y159098I-202J0D01*
G01X506700D01*
G37*
G36*
G01X511811Y241570D02*
G02Y238746I0J-1412D01*
G01X507873D01*
G02X507874Y241570I1J1412D01*
G01X511811D01*
G37*
G36*
G01X458104Y216536D02*
G02X455282I-1411J0D01*
G01Y220474D01*
G02X458104Y220473I1411J-1D01*
G01Y216536D01*
G37*
G36*
G01X462042D02*
G02X459218I-1412J0D01*
G01Y220474D01*
G02X462042Y220473I1412J-1D01*
G01Y216536D01*
G37*
G36*
G01X465978D02*
G02X463156I-1411J0D01*
G01Y220474D01*
G02X465978Y220473I1411J-1D01*
G01Y216536D01*
G37*
G36*
G01X469916D02*
G02X467092I-1412J0D01*
G01Y220474D01*
G02X469916Y220473I1412J-1D01*
G01Y216536D01*
G37*
G36*
G01X473852D02*
G02X471030I-1411J0D01*
G01Y220474D01*
G02X473852Y220473I1411J-1D01*
G01Y216536D01*
G37*
G36*
G01X477790D02*
G02X474966I-1412J0D01*
G01Y220474D01*
G02X477790Y220473I1412J-1D01*
G01Y216536D01*
G37*
G36*
G01X481726D02*
G02X478904I-1411J0D01*
G01Y220474D01*
G02X481726Y220473I1411J-1D01*
G01Y216536D01*
G37*
G36*
G01X485664D02*
G02X482840I-1412J0D01*
G01Y220474D01*
G02X485664Y220473I1412J-1D01*
G01Y216536D01*
G37*
G36*
G01X489600D02*
G02X486778I-1411J0D01*
G01Y220474D01*
G02X489600Y220473I1411J-1D01*
G01Y216536D01*
G37*
G36*
G01X500000Y237632D02*
G02Y234810I0J-1411D01*
G01X496062D01*
G02X496063Y237632I1J1411D01*
G01X500000D01*
G37*
G36*
G01Y233696D02*
G02Y230872I0J-1412D01*
G01X496062D01*
G02X496063Y233696I1J1412D01*
G01X500000D01*
G37*
G36*
G01Y229758D02*
G02Y226936I0J-1411D01*
G01X496062D01*
G02X496063Y229758I1J1411D01*
G01X500000D01*
G37*
G36*
G01Y225822D02*
G02Y222998I0J-1412D01*
G01X496062D01*
G02X496063Y225822I1J1412D01*
G01X500000D01*
G37*
G36*
G01Y221884D02*
G02Y219062I0J-1411D01*
G01X496062D01*
G02X496063Y221884I1J1411D01*
G01X500000D01*
G37*
G36*
G01Y217948D02*
G02Y215124I0J-1412D01*
G01X496062D01*
G02X496063Y217948I1J1412D01*
G01X500000D01*
G37*
G36*
G01Y214010D02*
G02Y211188I0J-1411D01*
G01X496062D01*
G02X496063Y214010I1J1411D01*
G01X500000D01*
G37*
G36*
G01X503937Y210074D02*
G02Y207250I0J-1412D01*
G01X499999D01*
G02X500000Y210074I1J1412D01*
G01X503937D01*
G37*
G36*
G01X500000Y241570D02*
G02Y238746I0J-1412D01*
G01X496062D01*
G02X496063Y241570I1J1412D01*
G01X500000D01*
G37*
G36*
G01X492678Y180547D02*
G02X489076I-1801J0D01*
G01Y185048D01*
G02X492678Y185047I1801J-1D01*
G01Y180547D01*
G37*
G36*
G01X502104Y180489D02*
G02X498500I-1802J0D01*
G01Y184990D01*
G02X502104Y184989I1802J-1D01*
G01Y180489D01*
G37*
G36*
G01X512228Y180431D02*
G02X508626I-1801J0D01*
G01Y184932D01*
G02X512228Y184931I1801J-1D01*
G01Y180431D01*
G37*
G36*
G01X489600Y204725D02*
G02X486778I-1411J0D01*
G01Y208663D01*
G02X489600Y208662I1411J-1D01*
G01Y204725D01*
G37*
G36*
G01X485664Y200788D02*
G02X482840I-1412J0D01*
G01Y204726D01*
G02X485664Y204725I1412J-1D01*
G01Y200788D01*
G37*
G36*
G01X481726Y204725D02*
G02X478904I-1411J0D01*
G01Y208663D01*
G02X481726Y208662I1411J-1D01*
G01Y204725D01*
G37*
G36*
G01X477790Y200788D02*
G02X474966I-1412J0D01*
G01Y204726D01*
G02X477790Y204725I1412J-1D01*
G01Y200788D01*
G37*
G36*
G01X473852Y204725D02*
G02X471030I-1411J0D01*
G01Y208663D01*
G02X473852Y208662I1411J-1D01*
G01Y204725D01*
G37*
G36*
G01X469916Y200788D02*
G02X467092I-1412J0D01*
G01Y204726D01*
G02X469916Y204725I1412J-1D01*
G01Y200788D01*
G37*
G36*
G01X465978Y204725D02*
G02X463156I-1411J0D01*
G01Y208663D01*
G02X465978Y208662I1411J-1D01*
G01Y204725D01*
G37*
G36*
G01X462042Y200788D02*
G02X459218I-1412J0D01*
G01Y204726D01*
G02X462042Y204725I1412J-1D01*
G01Y200788D01*
G37*
G36*
G01X458104Y204725D02*
G02X455282I-1411J0D01*
G01Y208663D01*
G02X458104Y208662I1411J-1D01*
G01Y204725D01*
G37*
G36*
G01X500000Y304562D02*
G02Y301738I0J-1412D01*
G01X496062D01*
G02X496063Y304562I1J1412D01*
G01X500000D01*
G37*
G36*
G01Y300624D02*
G02Y297802I0J-1411D01*
G01X496062D01*
G02X496063Y300624I1J1411D01*
G01X500000D01*
G37*
G36*
G01Y292750D02*
G02Y289928I0J-1411D01*
G01X496062D01*
G02X496063Y292750I1J1411D01*
G01X500000D01*
G37*
G36*
G01X515748Y245506D02*
G02Y242684I0J-1411D01*
G01X511810D01*
G02X511811Y245506I1J1411D01*
G01X515748D01*
G37*
G36*
G01X511811Y249444D02*
G02Y246620I0J-1412D01*
G01X507873D01*
G02X507874Y249444I1J1412D01*
G01X511811D01*
G37*
G36*
G01X515748Y253380D02*
G02Y250558I0J-1411D01*
G01X511810D01*
G02X511811Y253380I1J1411D01*
G01X515748D01*
G37*
G36*
G01X511811Y257318D02*
G02Y254494I0J-1412D01*
G01X507873D01*
G02X507874Y257318I1J1412D01*
G01X511811D01*
G37*
G36*
G01Y269128D02*
G02Y266306I0J-1411D01*
G01X507873D01*
G02X507874Y269128I1J1411D01*
G01X511811D01*
G37*
G36*
G01Y277002D02*
G02Y274180I0J-1411D01*
G01X507873D01*
G02X507874Y277002I1J1411D01*
G01X511811D01*
G37*
G36*
G01X515748Y280940D02*
G02Y278116I0J-1412D01*
G01X511810D01*
G02X511811Y280940I1J1412D01*
G01X515748D01*
G37*
G36*
G01X511811Y284876D02*
G02Y282054I0J-1411D01*
G01X507873D01*
G02X507874Y284876I1J1411D01*
G01X511811D01*
G37*
G36*
G01X500000Y257318D02*
G02Y254494I0J-1412D01*
G01X496062D01*
G02X496063Y257318I1J1412D01*
G01X500000D01*
G37*
G36*
G01Y253380D02*
G02Y250558I0J-1411D01*
G01X496062D01*
G02X496063Y253380I1J1411D01*
G01X500000D01*
G37*
G36*
G01Y245506D02*
G02Y242684I0J-1411D01*
G01X496062D01*
G02X496063Y245506I1J1411D01*
G01X500000D01*
G37*
G36*
G01Y261254D02*
G02Y258432I0J-1411D01*
G01X496062D01*
G02X496063Y261254I1J1411D01*
G01X500000D01*
G37*
G36*
G01Y269128D02*
G02Y266306I0J-1411D01*
G01X496062D01*
G02X496063Y269128I1J1411D01*
G01X500000D01*
G37*
G36*
G01Y273066D02*
G02Y270242I0J-1412D01*
G01X496062D01*
G02X496063Y273066I1J1412D01*
G01X500000D01*
G37*
G36*
G01Y277002D02*
G02Y274180I0J-1411D01*
G01X496062D01*
G02X496063Y277002I1J1411D01*
G01X500000D01*
G37*
G36*
G01Y280940D02*
G02Y278116I0J-1412D01*
G01X496062D01*
G02X496063Y280940I1J1412D01*
G01X500000D01*
G37*
G36*
G01Y284876D02*
G02Y282054I0J-1411D01*
G01X496062D01*
G02X496063Y284876I1J1411D01*
G01X500000D01*
G37*
G36*
G01Y288814D02*
G02Y285990I0J-1412D01*
G01X496062D01*
G02X496063Y288814I1J1412D01*
G01X500000D01*
G37*
G36*
G01Y249444D02*
G02Y246620I0J-1412D01*
G01X496062D01*
G02X496063Y249444I1J1412D01*
G01X500000D01*
G37*
G36*
G01X515748Y273066D02*
G02Y270242I0J-1412D01*
G01X511810D01*
G02X511811Y273066I1J1412D01*
G01X515748D01*
G37*
G36*
G01Y288814D02*
G02Y285990I0J-1412D01*
G01X511810D01*
G02X511811Y288814I1J1412D01*
G01X515748D01*
G37*
G36*
G01X500000Y296688D02*
G02Y293864I0J-1412D01*
G01X496062D01*
G02X496063Y296688I1J1412D01*
G01X500000D01*
G37*
G36*
G01X515748Y261254D02*
G02Y258432I0J-1411D01*
G01X511810D01*
G02X511811Y261254I1J1411D01*
G01X515748D01*
G37*
G36*
G01X574652Y38583D02*
G02X570230I-2211J0D01*
G01Y44096D01*
G02X574652Y44095I2211J-1D01*
G01Y38583D01*
G37*
G36*
G01X567566Y43307D02*
G02X563144I-2211J0D01*
G01Y48820D01*
G02X567566Y48819I2211J-1D01*
G01Y43307D01*
G37*
G36*
G01X560480Y38583D02*
G02X556056I-2212J0D01*
G01Y44096D01*
G02X560480Y44095I2212J-1D01*
G01Y38583D01*
G37*
G36*
G01X553392Y43307D02*
G02X548970I-2211J0D01*
G01Y48820D01*
G02X553392Y48819I2211J-1D01*
G01Y43307D01*
G37*
G36*
G01X546306Y38583D02*
G02X541884I-2211J0D01*
G01Y44096D01*
G02X546306Y44095I2211J-1D01*
G01Y38583D01*
G37*
G36*
G01X539220Y43307D02*
G02X534796I-2212J0D01*
G01Y48820D01*
G02X539220Y48819I2212J-1D01*
G01Y43307D01*
G37*
G36*
G01X532134Y38583D02*
G02X527710I-2212J0D01*
G01Y44096D01*
G02X532134Y44095I2212J-1D01*
G01Y38583D01*
G37*
G36*
G01X525046Y43307D02*
G02X520624I-2211J0D01*
G01Y48820D01*
G02X525046Y48819I2211J-1D01*
G01Y43307D01*
G37*
G36*
G01Y14961D02*
G02X520624I-2211J0D01*
G01Y20474D01*
G02X525046Y20473I2211J-1D01*
G01Y14961D01*
G37*
G36*
G01X532134Y10237D02*
G02X527710I-2212J0D01*
G01Y15749D01*
G02X532134Y15748I2212J-1D01*
G01Y10237D01*
G37*
G36*
G01X539220Y14961D02*
G02X534796I-2212J0D01*
G01Y20474D01*
G02X539220Y20473I2212J-1D01*
G01Y14961D01*
G37*
G36*
G01X546306Y10237D02*
G02X541884I-2211J0D01*
G01Y15749D01*
G02X546306Y15748I2211J-1D01*
G01Y10237D01*
G37*
G36*
G01X553392Y14961D02*
G02X548970I-2211J0D01*
G01Y20474D01*
G02X553392Y20473I2211J-1D01*
G01Y14961D01*
G37*
G36*
G01X560480Y10237D02*
G02X556056I-2212J0D01*
G01Y15749D01*
G02X560480Y15748I2212J-1D01*
G01Y10237D01*
G37*
G36*
G01X567566Y14961D02*
G02X563144I-2211J0D01*
G01Y20474D01*
G02X567566Y20473I2211J-1D01*
G01Y14961D01*
G37*
G36*
G01X574652Y10237D02*
G02X570230I-2211J0D01*
G01Y15749D01*
G02X574652Y15748I2211J-1D01*
G01Y10237D01*
G37*
G36*
G01X514655Y172920D02*
G02X514454Y173122I1J202D01*
G01Y176322D01*
G02X514655Y176524I201J1D01*
G01X515455D01*
G02X515656Y176322I-1J-202D01*
G01Y173122D01*
G02X515455Y172920I-201J-1D01*
G01X514655D01*
G37*
G36*
G01X516855D02*
G02X516654Y173122I1J202D01*
G01Y176322D01*
G02X516855Y176524I201J1D01*
G01X517655D01*
G02X517856Y176322I-1J-202D01*
G01Y173122D01*
G02X517655Y172920I-201J-1D01*
G01X516855D01*
G37*
G36*
G01X524300Y172998D02*
G02X524098Y173200I0J202D01*
G01Y176400D01*
G02X524300Y176602I202J0D01*
G01X525100D01*
G02X525302Y176400I0J-202D01*
G01Y173200D01*
G02X525100Y172998I-202J0D01*
G01X524300D01*
G37*
G36*
G01X526500D02*
G02X526298Y173200I0J202D01*
G01Y176400D01*
G02X526500Y176602I202J0D01*
G01X527300D01*
G02X527502Y176400I0J-202D01*
G01Y173200D01*
G02X527300Y172998I-202J0D01*
G01X526500D01*
G37*
G36*
G01X574170Y131409D02*
G02X577694Y132157I1762J374D01*
G01X578620Y127796D01*
X578621Y127794D01*
G02X575106Y127007I-1753J-413D01*
G01X574170Y131409D01*
G37*
G36*
G01X547365Y238846D02*
G02Y242430I0J1792D01*
G01X551866D01*
G02X551865Y238846I-1J-1792D01*
G01X547365D01*
G37*
G36*
G01X549000Y230108D02*
G02Y233692I0J1792D01*
G01X553501D01*
G02X553500Y230108I-1J-1792D01*
G01X549000D01*
G37*
G36*
G01X530493Y220166D02*
G02X530292Y220367I0J201D01*
G01Y223567D01*
G02X530493Y223768I201J0D01*
G01X531293D01*
G02X531494Y223567I0J-201D01*
G01Y220367D01*
G02X531293Y220166I-201J0D01*
G01X530493D01*
G37*
G36*
G01X532693D02*
G02X532492Y220367I0J201D01*
G01Y223567D01*
G02X532693Y223768I201J0D01*
G01X533493D01*
G02X533694Y223567I0J-201D01*
G01Y220367D01*
G02X533493Y220166I-201J0D01*
G01X532693D01*
G37*
G36*
G01X522354Y180373D02*
G02X518750I-1802J0D01*
G01Y184874D01*
G02X522354Y184873I1802J-1D01*
G01Y180373D01*
G37*
G36*
G01X531520Y239556D02*
G02X531318Y239757I-1J201D01*
G01Y242957D01*
G02X531520Y243158I202J-1D01*
G01X532320D01*
G02X532522Y242957I1J-201D01*
G01Y239757D01*
G02X532320Y239556I-202J1D01*
G01X531520D01*
G37*
G36*
G01X533720D02*
G02X533518Y239757I-1J201D01*
G01Y242957D01*
G02X533720Y243158I202J-1D01*
G01X534520D01*
G02X534722Y242957I1J-201D01*
G01Y239757D01*
G02X534520Y239556I-202J1D01*
G01X533720D01*
G37*
G36*
G01X527901Y255566D02*
G02X527700Y255767I0J201D01*
G01Y256567D01*
G02X527901Y256768I201J0D01*
G01X531101D01*
G02X531302Y256567I0J-201D01*
G01Y255767D01*
G02X531101Y255566I-201J0D01*
G01X527901D01*
G37*
G36*
G01Y253366D02*
G02X527700Y253567I0J201D01*
G01Y254367D01*
G02X527901Y254568I201J0D01*
G01X531101D01*
G02X531302Y254367I0J-201D01*
G01Y253567D01*
G02X531101Y253366I-201J0D01*
G01X527901D01*
G37*
G36*
G01X539600Y260298D02*
G02X539398Y260500I0J202D01*
G01Y261300D01*
G02X539600Y261502I202J0D01*
G01X542800D01*
G02X543002Y261300I0J-202D01*
G01Y260500D01*
G02X542800Y260298I-202J0D01*
G01X539600D01*
G37*
G36*
G01Y262498D02*
G02X539398Y262700I0J202D01*
G01Y263500D01*
G02X539600Y263702I202J0D01*
G01X542800D01*
G02X543002Y263500I0J-202D01*
G01Y262700D01*
G02X542800Y262498I-202J0D01*
G01X539600D01*
G37*
G36*
G01Y266298D02*
G02X539398Y266500I0J202D01*
G01Y267300D01*
G02X539600Y267502I202J0D01*
G01X542800D01*
G02X543002Y267300I0J-202D01*
G01Y266500D01*
G02X542800Y266298I-202J0D01*
G01X539600D01*
G37*
G36*
G01Y268498D02*
G02X539398Y268700I0J202D01*
G01Y269500D01*
G02X539600Y269702I202J0D01*
G01X542800D01*
G02X543002Y269500I0J-202D01*
G01Y268700D01*
G02X542800Y268498I-202J0D01*
G01X539600D01*
G37*
G36*
G01Y272398D02*
G02X539398Y272600I0J202D01*
G01Y273400D01*
G02X539600Y273602I202J0D01*
G01X542800D01*
G02X543002Y273400I0J-202D01*
G01Y272600D01*
G02X542800Y272398I-202J0D01*
G01X539600D01*
G37*
G36*
G01Y274598D02*
G02X539398Y274800I0J202D01*
G01Y275600D01*
G02X539600Y275802I202J0D01*
G01X542800D01*
G02X543002Y275600I0J-202D01*
G01Y274800D01*
G02X542800Y274598I-202J0D01*
G01X539600D01*
G37*
G36*
G01Y278498D02*
G02X539398Y278700I0J202D01*
G01Y279500D01*
G02X539600Y279702I202J0D01*
G01X542800D01*
G02X543002Y279500I0J-202D01*
G01Y278700D01*
G02X542800Y278498I-202J0D01*
G01X539600D01*
G37*
G36*
G01Y280698D02*
G02X539398Y280900I0J202D01*
G01Y281700D01*
G02X539600Y281902I202J0D01*
G01X542800D01*
G02X543002Y281700I0J-202D01*
G01Y280900D01*
G02X542800Y280698I-202J0D01*
G01X539600D01*
G37*
G36*
G01Y284598D02*
G02X539398Y284800I0J202D01*
G01Y285600D01*
G02X539600Y285802I202J0D01*
G01X542800D01*
G02X543002Y285600I0J-202D01*
G01Y284800D01*
G02X542800Y284598I-202J0D01*
G01X539600D01*
G37*
G36*
G01Y286798D02*
G02X539398Y287000I0J202D01*
G01Y287800D01*
G02X539600Y288002I202J0D01*
G01X542800D01*
G02X543002Y287800I0J-202D01*
G01Y287000D01*
G02X542800Y286798I-202J0D01*
G01X539600D01*
G37*
G36*
G01X539400Y290898D02*
G02X539198Y291100I0J202D01*
G01Y291900D01*
G02X539400Y292102I202J0D01*
G01X542600D01*
G02X542802Y291900I0J-202D01*
G01Y291100D01*
G02X542600Y290898I-202J0D01*
G01X539400D01*
G37*
G36*
G01Y293098D02*
G02X539198Y293300I0J202D01*
G01Y294100D01*
G02X539400Y294302I202J0D01*
G01X542600D01*
G02X542802Y294100I0J-202D01*
G01Y293300D01*
G02X542600Y293098I-202J0D01*
G01X539400D01*
G37*
G36*
G01X534500Y296998D02*
G02X534298Y297200I0J202D01*
G01Y298000D01*
G02X534500Y298202I202J0D01*
G01X537700D01*
G02X537902Y298000I0J-202D01*
G01Y297200D01*
G02X537700Y296998I-202J0D01*
G01X534500D01*
G37*
G36*
G01Y299198D02*
G02X534298Y299400I0J202D01*
G01Y300200D01*
G02X534500Y300402I202J0D01*
G01X537700D01*
G02X537902Y300200I0J-202D01*
G01Y299400D01*
G02X537700Y299198I-202J0D01*
G01X534500D01*
G37*
G36*
G01X546217Y254004D02*
G02Y257588I0J1792D01*
G01X550718D01*
G02X550717Y254004I-1J-1792D01*
G01X546217D01*
G37*
G36*
G01X546475Y246418D02*
G02Y250000I0J1791D01*
G01X550976D01*
G02X550975Y246418I-1J-1791D01*
G01X546475D01*
G37*
G36*
G01X545015Y302778D02*
X545129Y302792D01*
X549757D01*
X549871Y302778D01*
G02Y299782I-178J-1498D01*
G01X549757Y299768D01*
X545193D01*
X545192Y299770D01*
X545116Y299773D01*
G02X545015Y302778I76J1507D01*
G37*
G36*
G01X546449Y325547D02*
X546563Y325560D01*
X551191D01*
X551305Y325547D01*
G02Y322551I-178J-1498D01*
G01X551191Y322538D01*
X546627D01*
X546626Y322539D01*
X546550Y322542D01*
G02X546449Y325547I76J1507D01*
G37*
G36*
G01X545100Y317236D02*
X545214Y317250D01*
X549842D01*
X549956Y317236D01*
G02Y314240I-178J-1498D01*
G01X549842Y314226D01*
X545278D01*
X545277Y314228D01*
X545201Y314231D01*
G02X545100Y317236I76J1507D01*
G37*
G36*
G01X545043Y310269D02*
X545157Y310282D01*
X549721D01*
X549722Y310281D01*
X549798Y310278D01*
G02X549899Y307273I-76J-1507D01*
G01X549785Y307260D01*
X545157D01*
X545043Y307273D01*
G02Y310269I178J1498D01*
G37*
G36*
G01X534800Y318798D02*
G02X534598Y319000I0J202D01*
G01Y319800D01*
G02X534800Y320002I202J0D01*
G01X538000D01*
G02X538202Y319800I0J-202D01*
G01Y319000D01*
G02X538000Y318798I-202J0D01*
G01X534800D01*
G37*
G36*
G01Y316598D02*
G02X534598Y316800I0J202D01*
G01Y317600D01*
G02X534800Y317802I202J0D01*
G01X538000D01*
G02X538202Y317600I0J-202D01*
G01Y316800D01*
G02X538000Y316598I-202J0D01*
G01X534800D01*
G37*
G36*
G01X534600Y306698D02*
G02X534398Y306900I0J202D01*
G01Y307700D01*
G02X534600Y307902I202J0D01*
G01X537800D01*
G02X538002Y307700I0J-202D01*
G01Y306900D01*
G02X537800Y306698I-202J0D01*
G01X534600D01*
G37*
G36*
G01Y304498D02*
G02X534398Y304700I0J202D01*
G01Y305500D01*
G02X534600Y305702I202J0D01*
G01X537800D01*
G02X538002Y305500I0J-202D01*
G01Y304700D01*
G02X537800Y304498I-202J0D01*
G01X534600D01*
G37*
G36*
G01X534700Y312798D02*
G02X534498Y313000I0J202D01*
G01Y313800D01*
G02X534700Y314002I202J0D01*
G01X537900D01*
G02X538102Y313800I0J-202D01*
G01Y313000D01*
G02X537900Y312798I-202J0D01*
G01X534700D01*
G37*
G36*
G01Y310598D02*
G02X534498Y310800I0J202D01*
G01Y311600D01*
G02X534700Y311802I202J0D01*
G01X537900D01*
G02X538102Y311600I0J-202D01*
G01Y310800D01*
G02X537900Y310598I-202J0D01*
G01X534700D01*
G37*
G36*
G01X588826Y38583D02*
G02X584402I-2212J0D01*
G01Y44096D01*
G02X588826Y44095I2212J-1D01*
G01Y38583D01*
G37*
G36*
G01X581740Y43307D02*
G02X577316I-2212J0D01*
G01Y48820D01*
G02X581740Y48819I2212J-1D01*
G01Y43307D01*
G37*
G36*
G01Y14961D02*
G02X577316I-2212J0D01*
G01Y20474D01*
G02X581740Y20473I2212J-1D01*
G01Y14961D01*
G37*
G36*
G01X588826Y10237D02*
G02X584402I-2212J0D01*
G01Y15749D01*
G02X588826Y15748I2212J-1D01*
G01Y10237D01*
G37*
G36*
G01X587008Y178059D02*
G02X590532Y178807I1762J374D01*
G01X591458Y174446D01*
X591459Y174444D01*
G02X587944Y173657I-1753J-413D01*
G01X587008Y178059D01*
G37*
G36*
G01X583383Y162435D02*
G02X586907Y163183I1762J374D01*
G01X587833Y158822D01*
X587834Y158820D01*
G02X584319Y158033I-1753J-413D01*
G01X583383Y162435D01*
G37*
G36*
G01X592704Y153607D02*
G02X596228Y154355I1762J374D01*
G01X597154Y149994D01*
X597155Y149992D01*
G02X593640Y149205I-1753J-413D01*
G01X592704Y153607D01*
G37*
G36*
G01X585372Y142248D02*
G02X588896Y142996I1762J374D01*
G01X589822Y138635D01*
X589823Y138633D01*
G02X586308Y137846I-1753J-413D01*
G01X585372Y142248D01*
G37*
G36*
G01X589961Y218883D02*
X590897Y214481D01*
G02X587373Y213733I-1762J-374D01*
G01X586447Y218094D01*
X586446Y218096D01*
G02X589961Y218883I1753J413D01*
G37*
G36*
G01X582312Y202511D02*
G02X585836Y203259I1762J374D01*
G01X586762Y198898D01*
X586763Y198896D01*
G02X583248Y198109I-1753J-413D01*
G01X582312Y202511D01*
G37*
G36*
G01X578187Y186887D02*
G02X581711Y187635I1762J374D01*
G01X582637Y183274D01*
X582638Y183272D01*
G02X579123Y182485I-1753J-413D01*
G01X578187Y186887D01*
G37*
G36*
G01X648907Y79234D02*
G02X648706Y79436I1J202D01*
G01Y82636D01*
G02X648907Y82838I201J1D01*
G01X649707D01*
G02X649908Y82636I-1J-202D01*
G01Y79436D01*
G02X649707Y79234I-201J-1D01*
G01X648907D01*
G37*
G36*
G01X651407D02*
G02X651206Y79436I1J202D01*
G01Y82636D01*
G02X651407Y82838I201J1D01*
G01X652207D01*
G02X652408Y82636I-1J-202D01*
G01Y79436D01*
G02X652207Y79234I-201J-1D01*
G01X651407D01*
G37*
G36*
G01X655680Y79194D02*
G02X655478Y79396I0J202D01*
G01Y82596D01*
G02X655680Y82798I202J0D01*
G01X656480D01*
G02X656682Y82596I0J-202D01*
G01Y79396D01*
G02X656480Y79194I-202J0D01*
G01X655680D01*
G37*
G36*
G01X658180D02*
G02X657978Y79396I0J202D01*
G01Y82596D01*
G02X658180Y82798I202J0D01*
G01X658980D01*
G02X659182Y82596I0J-202D01*
G01Y79396D01*
G02X658980Y79194I-202J0D01*
G01X658180D01*
G37*
G36*
G01X664885Y80902D02*
G02X664684Y81104I1J202D01*
G01Y84304D01*
G02X664885Y84506I201J1D01*
G01X665685D01*
G02X665886Y84304I-1J-202D01*
G01Y81104D01*
G02X665685Y80902I-201J-1D01*
G01X664885D01*
G37*
G36*
G01X667150Y80892D02*
G02X666948Y81094I0J202D01*
G01Y84294D01*
G02X667150Y84496I202J0D01*
G01X667950D01*
G02X668152Y84294I0J-202D01*
G01Y81094D01*
G02X667950Y80892I-202J0D01*
G01X667150D01*
G37*
G36*
G01X672526Y80428D02*
G02X672324Y80630I0J202D01*
G01Y83830D01*
G02X672526Y84032I202J0D01*
G01X673326D01*
G02X673528Y83830I0J-202D01*
G01Y80630D01*
G02X673326Y80428I-202J0D01*
G01X672526D01*
G37*
G36*
G01X674926D02*
G02X674724Y80630I0J202D01*
G01Y83830D01*
G02X674926Y84032I202J0D01*
G01X675726D01*
G02X675928Y83830I0J-202D01*
G01Y80630D01*
G02X675726Y80428I-202J0D01*
G01X674926D01*
G37*
G36*
G01X680883D02*
G02X680682Y80629I0J201D01*
G01Y83829D01*
G02X680883Y84030I201J0D01*
G01X681683D01*
G02X681884Y83829I0J-201D01*
G01Y80629D01*
G02X681683Y80428I-201J0D01*
G01X680883D01*
G37*
G36*
G01X683163D02*
G02X682962Y80630I1J202D01*
G01Y83830D01*
G02X683163Y84032I201J1D01*
G01X683963D01*
G02X684164Y83830I-1J-202D01*
G01Y80630D01*
G02X683963Y80428I-201J-1D01*
G01X683163D01*
G37*
G36*
G01X688749Y80696D02*
G02X688548Y80898I1J202D01*
G01Y84098D01*
G02X688749Y84300I201J1D01*
G01X689549D01*
G02X689750Y84098I-1J-202D01*
G01Y80898D01*
G02X689549Y80696I-201J-1D01*
G01X688749D01*
G37*
G36*
G01X690982Y80698D02*
G02X690780Y80899I-1J201D01*
G01Y84099D01*
G02X690982Y84300I202J-1D01*
G01X691782D01*
G02X691984Y84099I1J-201D01*
G01Y80899D01*
G02X691782Y80698I-202J1D01*
G01X690982D01*
G37*
G36*
G01X695876Y90958D02*
G02X692854I-1511J0D01*
G01Y94459D01*
G02X695876Y94458I1511J-1D01*
G01Y90958D01*
G37*
G36*
G01X687790Y90994D02*
G02X684768I-1511J0D01*
G01Y94495D01*
G02X687790Y94494I1511J-1D01*
G01Y90994D01*
G37*
G36*
G01X679736Y90996D02*
G02X676714I-1511J0D01*
G01Y94497D01*
G02X679736Y94496I1511J-1D01*
G01Y90996D01*
G37*
G36*
G01X671658Y91005D02*
G02X668634I-1512J0D01*
G01Y94506D01*
G02X671658Y94505I1512J-1D01*
G01Y91005D01*
G37*
G36*
G01X663558Y91039D02*
G02X660536I-1511J0D01*
G01Y94540D01*
G02X663558Y94539I1511J-1D01*
G01Y91039D01*
G37*
G36*
G01X655548Y91208D02*
G02X652526I-1511J0D01*
G01Y94709D01*
G02X655548Y94708I1511J-1D01*
G01Y91208D01*
G37*
G36*
G01X710872Y43307D02*
G02X706450I-2211J0D01*
G01Y48820D01*
G02X710872Y48819I2211J-1D01*
G01Y43307D01*
G37*
G36*
G01X753392D02*
G02X748970I-2211J0D01*
G01Y48820D01*
G02X753392Y48819I2211J-1D01*
G01Y43307D01*
G37*
G36*
G01X717960Y38583D02*
G02X713536I-2212J0D01*
G01Y44096D01*
G02X717960Y44095I2212J-1D01*
G01Y38583D01*
G37*
G36*
G01X725046Y43307D02*
G02X720622I-2212J0D01*
G01Y48820D01*
G02X725046Y48819I2212J-1D01*
G01Y43307D01*
G37*
G36*
G01X760478Y38583D02*
G02X756056I-2211J0D01*
G01Y44096D01*
G02X760478Y44095I2211J-1D01*
G01Y38583D01*
G37*
G36*
G01X746306D02*
G02X741882I-2212J0D01*
G01Y44096D01*
G02X746306Y44095I2212J-1D01*
G01Y38583D01*
G37*
G36*
G01X739218Y43307D02*
G02X734796I-2211J0D01*
G01Y48820D01*
G02X739218Y48819I2211J-1D01*
G01Y43307D01*
G37*
G36*
G01X732132Y38583D02*
G02X727710I-2211J0D01*
G01Y44096D01*
G02X732132Y44095I2211J-1D01*
G01Y38583D01*
G37*
G36*
G01X710872Y14961D02*
G02X706450I-2211J0D01*
G01Y20474D01*
G02X710872Y20473I2211J-1D01*
G01Y14961D01*
G37*
G36*
G01X717960Y10237D02*
G02X713536I-2212J0D01*
G01Y15749D01*
G02X717960Y15748I2212J-1D01*
G01Y10237D01*
G37*
G36*
G01X725046Y14961D02*
G02X720622I-2212J0D01*
G01Y20474D01*
G02X725046Y20473I2212J-1D01*
G01Y14961D01*
G37*
G36*
G01X732132Y10237D02*
G02X727710I-2211J0D01*
G01Y15749D01*
G02X732132Y15748I2211J-1D01*
G01Y10237D01*
G37*
G36*
G01X739218Y14961D02*
G02X734796I-2211J0D01*
G01Y20474D01*
G02X739218Y20473I2211J-1D01*
G01Y14961D01*
G37*
G36*
G01X746306Y10237D02*
G02X741882I-2212J0D01*
G01Y15749D01*
G02X746306Y15748I2212J-1D01*
G01Y10237D01*
G37*
G36*
G01X753392Y14961D02*
G02X748970I-2211J0D01*
G01Y20474D01*
G02X753392Y20473I2211J-1D01*
G01Y14961D01*
G37*
G36*
G01X760478Y10237D02*
G02X756056I-2211J0D01*
G01Y15749D01*
G02X760478Y15748I2211J-1D01*
G01Y10237D01*
G37*
G36*
G01X710872Y29134D02*
G02X706450I-2211J0D01*
G01Y34647D01*
G02X710872Y34646I2211J-1D01*
G01Y29134D01*
G37*
G36*
G01X704246Y82870D02*
G02X704044Y82668I-202J0D01*
G01X700844D01*
G02X700642Y82870I0J202D01*
G01Y83670D01*
G02X700844Y83872I202J0D01*
G01X704044D01*
G02X704246Y83670I0J-202D01*
G01Y82870D01*
G37*
G36*
G01X704242Y80623D02*
G02X704041Y80422I-201J0D01*
G01X700841D01*
G02X700640Y80623I0J201D01*
G01Y81423D01*
G02X700841Y81624I201J0D01*
G01X704041D01*
G02X704242Y81423I0J-201D01*
G01Y80623D01*
G37*
G36*
G01X715460Y85592D02*
G02X715259Y85390I-201J-1D01*
G01X712059D01*
G02X711858Y85592I1J202D01*
G01Y86392D01*
G02X712059Y86594I201J1D01*
G01X715259D01*
G02X715460Y86392I-1J-202D01*
G01Y85592D01*
G37*
G36*
G01X715462Y83360D02*
G02X715260Y83158I-202J0D01*
G01X712060D01*
G02X711858Y83360I0J202D01*
G01Y84160D01*
G02X712060Y84362I202J0D01*
G01X715260D01*
G02X715462Y84160I0J-202D01*
G01Y83360D01*
G37*
G36*
G01X711890Y92899D02*
G02X708866I-1512J0D01*
G01Y96400D01*
G02X711890Y96399I1512J-1D01*
G01Y92899D01*
G37*
G36*
G01X703902Y91010D02*
G02X700880I-1511J0D01*
G01Y94511D01*
G02X703902Y94510I1511J-1D01*
G01Y91010D01*
G37*
G54D46*
X137795Y472441D03*
X98425D03*
G54D41*
X798456Y26432D03*
X81539Y542850D03*
X27058Y25484D03*
G54D44*
X437008Y460630D03*
X389764D03*
G54D47*
X116063Y14567D03*
G54D45*
X295276Y531496D03*
G54D40*
X781496Y198819D03*
X531496Y371299D03*
G54D43*
Y531496D03*
G54D42*
X596457Y116142D03*
X374016Y156221D03*
G54D48*
X116066Y39074D03*
G54D17*
X37402Y517441D03*
X789370D03*
G54D14*
X54697Y165269D03*
X58697D03*
X59600Y152000D03*
X71200Y137200D03*
X39416Y206616D03*
X65500Y237800D03*
X70500D03*
X75500D03*
X23800Y211200D03*
X27500D03*
X59700Y178600D03*
X68400Y177950D03*
X76800Y178200D03*
X46194Y179835D03*
X50194D03*
X39320Y213823D03*
X64000Y178400D03*
X72800Y178200D03*
X22150Y203550D03*
X26150Y230850D03*
X23100Y283200D03*
X22750Y275450D03*
X23500Y296700D03*
X68300Y292200D03*
X45650Y250280D03*
X49320D03*
X40290Y239814D03*
X35405Y239808D03*
X32469Y250280D03*
X37469D03*
X52450Y333850D03*
X31450Y334050D03*
X74150Y334250D03*
X28000Y326500D03*
X24000Y301750D03*
X23400Y309500D03*
X67800Y318000D03*
X67700Y321500D03*
X58900Y334180D03*
X62325Y334068D03*
X37900Y334380D03*
X41325Y334268D03*
X65500Y378800D03*
X43000Y378233D03*
X22000Y378352D03*
X53500Y403150D03*
X49700Y402000D03*
X50700Y378233D03*
X54800Y373600D03*
X29900Y378252D03*
X38200Y373800D03*
X34100D03*
X73100Y378700D03*
X60400Y373600D03*
X77200Y374000D03*
X65375Y392835D03*
X35800Y363400D03*
X40100D03*
X92300Y199400D03*
Y209400D03*
Y204400D03*
X90800Y217900D03*
X82600Y232000D03*
X78850Y221000D03*
X87300Y230650D03*
X92300Y190900D03*
X81300Y178050D03*
X85700Y178000D03*
X92300Y194900D03*
X78800Y205900D03*
X92300Y213900D03*
X89800Y178000D03*
X80688Y281695D03*
Y276695D03*
X93884Y242333D03*
X102300Y329100D03*
X95245Y334043D03*
X80700Y309400D03*
X80600Y304600D03*
Y334580D03*
X84025Y334468D03*
X102400Y333900D03*
X106500D03*
X85795Y378426D03*
X102395Y373793D03*
X93695Y378426D03*
X81300Y374000D03*
X98295Y373793D03*
X106709Y383400D03*
X112023Y383013D03*
X78171Y363195D03*
X82171D03*
X99266Y362988D03*
X103266D03*
X104900Y412200D03*
X102679Y391150D03*
X112638Y391197D03*
X107582Y391266D03*
X182100Y105500D03*
X155991Y110061D03*
X200550Y111350D03*
X152800Y113400D03*
X164020Y101127D03*
X158612Y126645D03*
X198202Y135298D03*
X201139Y121630D03*
X172800Y141001D03*
X180300Y175400D03*
X145585Y132451D03*
X197100Y298800D03*
X162522Y331774D03*
X196600Y306800D03*
X250137Y36053D03*
X261499Y55353D03*
X257499D03*
X241750Y98250D03*
X238867Y63650D03*
X255300Y72600D03*
X234693Y57400D03*
X255154Y69177D03*
X233759Y64752D03*
X220228Y63651D03*
X204400Y288700D03*
X248900Y282932D03*
X259629Y281000D03*
X242351Y282900D03*
X228300Y280900D03*
X219400Y279400D03*
X262800Y277835D03*
X242400Y289700D03*
X242402Y286300D03*
X225500Y278900D03*
X222320Y277658D03*
X207500Y278400D03*
X204997Y280702D03*
X222000Y310600D03*
X231700Y320100D03*
X249775Y320167D03*
X214700Y320200D03*
X212198Y328316D03*
X208648Y328452D03*
X261365Y324351D03*
X245943Y326300D03*
X246100Y329700D03*
X230400Y326200D03*
Y329600D03*
X253245Y329698D03*
X253154Y326227D03*
X241556Y340111D03*
X237483Y339988D03*
X230000Y336500D03*
X233400Y336600D03*
X218400Y326600D03*
X218300Y330000D03*
X230400Y348000D03*
X255500Y423361D03*
X256172Y409530D03*
X261996Y365663D03*
X263250Y423411D03*
X257996Y365663D03*
X259800Y423400D03*
X256900Y380900D03*
X281700Y52285D03*
X285500D03*
X308591Y68928D03*
X304591D03*
X308591Y73074D03*
X311182Y58692D03*
X276700Y66700D03*
X283385Y100227D03*
X287385D03*
X319533Y114283D03*
X291385Y100227D03*
X295385D03*
X306196Y110209D03*
X310711Y113820D03*
X314772Y108292D03*
X300311Y60800D03*
X300385Y108227D03*
X311182Y62800D03*
X272937Y90362D03*
X266895Y100227D03*
X306280Y82574D03*
X283393Y92325D03*
X301280Y82574D03*
X272937Y85862D03*
X304591Y73074D03*
X318773Y108083D03*
X278039Y82185D03*
X279385Y100227D03*
X292030Y90574D03*
X292385Y108227D03*
X280298Y95556D03*
X296280Y82574D03*
X324026Y115936D03*
X321343Y122343D03*
X321051Y134028D03*
X304529Y118792D03*
X317600Y278800D03*
X319543Y290159D03*
X303032Y289900D03*
X268400Y281000D03*
X266406Y277835D03*
X306292Y252825D03*
X302262Y262642D03*
X299635Y288650D03*
X292225Y288267D03*
X297021Y346579D03*
X287350Y351200D03*
X319550Y347169D03*
X305147Y354706D03*
X316050Y342200D03*
X287350Y357700D03*
X322500Y353700D03*
X301500Y337500D03*
X320650Y336456D03*
X306060Y337640D03*
X310200Y337600D03*
X280800Y325000D03*
X290750D03*
X280217Y350927D03*
X269365Y320351D03*
X325500Y325400D03*
X314241Y308459D03*
X314300Y311900D03*
X308180Y305200D03*
X305628Y320511D03*
X301628D03*
X325500Y321400D03*
X314400Y327851D03*
X314045Y302900D03*
X314500Y324251D03*
X319100Y330600D03*
X305628Y324511D03*
X324100Y307814D03*
X265365Y324351D03*
X281150Y332000D03*
X288536Y314764D03*
X275696Y314340D03*
X308398Y386479D03*
X304205Y382450D03*
X304398Y386479D03*
X292800Y363800D03*
X300019Y379524D03*
X296079D03*
X325200Y365100D03*
X312398Y386479D03*
X270618Y385867D03*
X268004Y424361D03*
X323448Y405064D03*
X266500Y364000D03*
X325629Y443510D03*
X328600Y114400D03*
X328711Y108053D03*
X335722Y94574D03*
X329722D03*
X374616Y172378D03*
X370061Y172433D03*
X355500Y144500D03*
X342000Y141600D03*
X331649Y126111D03*
X339049Y124238D03*
X335994Y126119D03*
X341913Y145049D03*
X374915Y176442D03*
X359969Y124510D03*
X349911Y136954D03*
X357546Y230354D03*
X360710Y231897D03*
X376306Y182715D03*
X351723Y178499D03*
X354143Y183439D03*
X362260Y184360D03*
X364169Y188366D03*
X366460Y191794D03*
X368558Y194540D03*
X379415Y194608D03*
X370570Y198219D03*
X371124Y178760D03*
X372517Y182362D03*
X380400Y287400D03*
X382000Y296500D03*
X384600Y285600D03*
X379000Y272600D03*
X384300Y291100D03*
X346900Y281300D03*
X343100D03*
X357996Y272841D03*
X328134Y252720D03*
X332000Y266336D03*
X376633Y261543D03*
X340280Y253765D03*
X337500Y266050D03*
X358096Y262268D03*
X341998Y256700D03*
X368610Y257299D03*
X376633Y256851D03*
X385887Y305222D03*
X381396Y302610D03*
X335400Y337400D03*
X345700Y349773D03*
X337600Y349600D03*
X339000Y344700D03*
X330000Y345800D03*
X335882Y309823D03*
X327400Y342600D03*
X386159Y337080D03*
X375148Y337184D03*
X382600Y337200D03*
X344000Y316000D03*
X346500Y302500D03*
X356550Y337200D03*
X348596Y337250D03*
X347750Y315850D03*
X352396Y337200D03*
X331026Y303354D03*
X328100Y331300D03*
X329364Y316949D03*
X364050Y337200D03*
X374250Y347600D03*
X359200Y315800D03*
X355200D03*
X360300Y323900D03*
X363400Y315800D03*
X344000Y388500D03*
X340375Y365944D03*
X331765Y386535D03*
X367450Y409955D03*
X338000Y421000D03*
X367350Y406455D03*
X360000Y410000D03*
X337592Y405027D03*
X448300Y337500D03*
X444100Y341000D03*
X444200Y337600D03*
X444100Y345000D03*
X440300Y337500D03*
X416822Y347133D03*
X412381Y347149D03*
X435000Y347800D03*
X441000D03*
X433500Y337500D03*
X426464Y347078D03*
X397000Y337000D03*
X401700Y337350D03*
X392959Y337099D03*
X405921Y347159D03*
X430464Y347078D03*
X390550Y326820D03*
X405783Y339318D03*
X448500Y424000D03*
X445000Y422000D03*
X452300Y337500D03*
X468300D03*
X456550D03*
X464300D03*
X460800Y337562D03*
X460300Y333500D03*
X502138Y348500D03*
X476500Y347650D03*
X498138Y348500D03*
X506200Y358809D03*
X493200Y358800D03*
X498700Y359209D03*
X452600Y332700D03*
X462450Y358960D03*
X472463Y329837D03*
X468500Y347500D03*
X476200Y334900D03*
X506262Y348500D03*
X510138D03*
X479640Y334674D03*
X503800Y382700D03*
X473900Y371800D03*
X485100Y363400D03*
X510200Y363209D03*
X506200D03*
X494400Y363800D03*
X499100Y363409D03*
X452500Y423500D03*
X510700Y367309D03*
X506700D03*
X489600Y367209D03*
X474200Y367500D03*
X457599Y419642D03*
X496300Y378935D03*
X489500Y371200D03*
X546627Y324049D03*
X551127D03*
X545278Y315738D03*
X549778D03*
X545221Y308771D03*
X549721D03*
X545193Y301280D03*
X549693D03*
X552200Y339300D03*
X556800D03*
X547225Y357997D03*
X547379Y338352D03*
X539900Y338300D03*
X534000Y338400D03*
X538225Y357997D03*
X555697Y356565D03*
X514000Y359209D03*
X514138Y348500D03*
X518138Y348350D03*
X525438Y350500D03*
X519263Y327092D03*
X538476Y334365D03*
X538436Y330918D03*
X534100Y342410D03*
X536200Y348300D03*
X540200D03*
X550100D03*
X546100D03*
X554685Y333410D03*
X547927Y342199D03*
X543646Y342347D03*
X539446D03*
X519629Y330448D03*
X521914Y332907D03*
X574250Y466900D03*
X545880Y485940D03*
X539040Y480090D03*
X562460Y457580D03*
X632416Y31609D03*
X627603Y43523D03*
X627500Y19339D03*
X626786Y31227D03*
X634400Y102000D03*
X630600D03*
X627500Y64500D03*
X629500Y61500D03*
X635852Y133715D03*
X636363Y209944D03*
X632363D03*
X628363D03*
X624363D03*
X622400Y216750D03*
X594025Y280017D03*
X631800Y316137D03*
X603650Y315500D03*
X594292Y362291D03*
X625000Y361700D03*
X590350Y323011D03*
X629250Y310491D03*
Y306491D03*
X626405Y314991D03*
X629250Y344900D03*
Y348900D03*
X623063Y357337D03*
X602649Y349033D03*
X594400Y357000D03*
Y353000D03*
X597450Y324750D03*
Y320750D03*
X584280Y424030D03*
X598023Y383081D03*
X624200Y372500D03*
X620260Y389940D03*
X589394Y384572D03*
X589391Y378202D03*
X627140Y381353D03*
X631140D03*
X594200Y395200D03*
X604832Y395220D03*
X581020Y471890D03*
X574667Y479799D03*
X577300Y460300D03*
X588400Y469450D03*
X634050Y469200D03*
X588663Y460037D03*
X581250Y480550D03*
X585420Y456480D03*
X633676Y460080D03*
X617000Y468700D03*
X588030Y430795D03*
X620600Y458500D03*
X656300Y20100D03*
X660200Y20200D03*
X647216Y31601D03*
X667900Y40800D03*
X643816Y31573D03*
X640144Y40969D03*
X643103Y13803D03*
X664301Y40104D03*
Y49998D03*
X638103Y13100D03*
X640416Y31609D03*
X647103Y13964D03*
X694365Y94458D03*
Y90958D03*
X686279Y94494D03*
Y90994D03*
X678225Y94496D03*
Y90996D03*
X670146Y94505D03*
Y91005D03*
X662047Y94539D03*
Y91039D03*
X654037Y94708D03*
Y91208D03*
X668100Y56100D03*
X651564Y52638D03*
X644500Y65759D03*
X657480Y113385D03*
X678189Y108784D03*
X689049Y109487D03*
X669500Y108400D03*
X640600Y111600D03*
X641003Y68809D03*
X660629Y170078D03*
Y173227D03*
X654330Y157480D03*
X651181Y154330D03*
X673229Y170079D03*
X679527Y173229D03*
X692126Y141732D03*
X698425D03*
X679527Y148031D03*
X685826D03*
X692126D03*
X698425D03*
X679527Y154330D03*
X685826D03*
X692126D03*
X698425D03*
Y160629D03*
X692126D03*
X685826D03*
X679527D03*
X698425Y166929D03*
X692126D03*
X685826D03*
X679527D03*
X698425Y173228D03*
X692126D03*
X685826D03*
X670078Y170078D03*
X654330Y173228D03*
X651181Y166929D03*
X676376Y132281D03*
X666929Y129134D03*
X660630Y160630D03*
X640775Y156218D03*
X648031Y157480D03*
X663779Y151181D03*
X666929Y148031D03*
X663779Y132283D03*
X663778Y144883D03*
Y138584D03*
X651181Y141732D03*
Y132283D03*
Y122834D03*
X644882Y154331D03*
X637952Y142515D03*
X640500Y125000D03*
X660629Y144883D03*
X657481Y132284D03*
X670078Y151181D03*
X637343Y171335D03*
Y174835D03*
X657480Y154330D03*
X644882Y173228D03*
Y176378D03*
Y170078D03*
X648031D03*
X670078Y157480D03*
X673228Y148031D03*
X692126Y125984D03*
X685827Y116535D03*
X670079Y125985D03*
X682678D03*
X676378D03*
X688977D03*
X676378Y119686D03*
X666929Y119685D03*
X663780Y125985D03*
X657479Y116536D03*
X654330Y116535D03*
Y119685D03*
Y122834D03*
X657480Y125984D03*
X654331D03*
X654330Y129134D03*
Y132283D03*
Y135433D03*
X651181D03*
X654330Y138582D03*
Y141732D03*
Y144882D03*
X651181D03*
X654330Y148031D03*
Y151181D03*
X679452Y209815D03*
X683913Y213313D03*
X695275Y198425D03*
X692125Y198423D03*
X686352Y207200D03*
X651181Y192125D03*
X663779D03*
X657480D03*
X670078D03*
X654330Y185826D03*
Y179526D03*
X685826Y192125D03*
X692125D03*
X667353Y233486D03*
X640363Y209944D03*
X638479Y230640D03*
X674023Y213815D03*
X640509Y177600D03*
X674172Y210095D03*
X679400Y213300D03*
X679527Y198424D03*
X697149Y219742D03*
X692949D03*
X695383Y266855D03*
X644153Y278745D03*
X660400Y271900D03*
X678500Y240324D03*
X691100Y240354D03*
X686900D03*
X668600Y242800D03*
X669450Y284900D03*
X695600Y244354D03*
X695375Y260875D03*
X637500Y362400D03*
X680300Y384900D03*
X674150Y415380D03*
X654770Y401166D03*
X645970Y399130D03*
X669031Y388383D03*
X665031D03*
X653360Y386210D03*
X680700Y378200D03*
X687150Y385550D03*
X675031Y389383D03*
X653007Y382828D03*
X658601Y401800D03*
X673900Y418880D03*
X637500Y365900D03*
X692200Y428700D03*
X681540Y429640D03*
X678700Y440950D03*
X671640Y454410D03*
X683250Y437813D03*
X710378Y96399D03*
Y92899D03*
X702391Y94510D03*
Y91010D03*
X722673Y105444D03*
X736785Y110185D03*
X737800Y106525D03*
X717197Y109646D03*
X726100Y107200D03*
X734709Y106595D03*
X731000Y106315D03*
X734212Y109995D03*
X725943Y100147D03*
X744833Y78995D03*
X754572Y86923D03*
X754528Y83228D03*
X745100Y97500D03*
X699563Y108815D03*
X719010Y107281D03*
X707649Y110002D03*
X710517Y106823D03*
X750773Y74636D03*
X747919Y76667D03*
X720744Y92427D03*
X704849Y107385D03*
X729921Y157480D03*
X739952Y120649D03*
X740952Y126815D03*
X707874Y116535D03*
X743100Y114700D03*
X737352Y145885D03*
X726771Y122835D03*
X729921Y122834D03*
X737702Y128565D03*
X729921Y132283D03*
Y129134D03*
X711023Y116535D03*
X726771Y163779D03*
X741754Y134617D03*
X729921Y135433D03*
X739622Y137008D03*
X729921Y138582D03*
Y144882D03*
X714173Y116535D03*
X717322D03*
X707873Y129133D03*
X720473Y116536D03*
X704725D03*
X704724Y148031D03*
Y154330D03*
Y160629D03*
Y166929D03*
Y173228D03*
X714173Y122834D03*
X720472D03*
X741077Y159790D03*
X757471Y148193D03*
X723621Y148031D03*
Y154330D03*
Y160629D03*
Y166929D03*
Y173228D03*
X707874Y122835D03*
X723621Y135433D03*
Y129133D03*
Y141732D03*
X701575Y122835D03*
X714173Y141732D03*
X723622Y116535D03*
X704723Y129133D03*
X701574D03*
X711022D03*
X714172D03*
X729921Y125984D03*
X711023Y173228D03*
X741952Y173115D03*
X738352Y174615D03*
X729920Y176378D03*
Y173229D03*
X736219Y170079D03*
X733070D03*
X746750Y157700D03*
X729921Y148031D03*
Y141732D03*
Y163779D03*
X750550Y135200D03*
X729921Y160629D03*
X701575Y116536D03*
X729921Y154330D03*
X730737Y235199D03*
X724465Y224741D03*
X714620Y221041D03*
X743460Y231900D03*
X701574Y192125D03*
X707873D03*
X714173D03*
X723621D03*
Y185826D03*
Y179527D03*
X715467Y210507D03*
X725009Y213292D03*
X739852Y195915D03*
X737832Y202664D03*
X729920Y188977D03*
X739752Y199615D03*
X738416Y190551D03*
X729920Y182678D03*
X745485Y197673D03*
Y201673D03*
X740352Y180115D03*
X729920Y185827D03*
X724776Y209963D03*
X743752Y187115D03*
X742502Y182715D03*
X742252Y177015D03*
X737315Y177952D03*
X733070Y179527D03*
X720819Y209800D03*
X729246Y209941D03*
X736272Y208181D03*
X729136Y206654D03*
X738839Y206080D03*
X733565Y210184D03*
X729920Y192126D03*
X720357Y207104D03*
X714173Y198425D03*
X729921Y179527D03*
X720471Y198424D03*
X731915Y206310D03*
X738952Y184215D03*
X744052Y193784D03*
X701574Y198424D03*
X711023Y198425D03*
X704724D03*
X717322D03*
X707873Y198424D03*
X723621D03*
X704724Y201574D03*
X706737Y205505D03*
X705336Y208437D03*
X711310Y207023D03*
X714173Y201574D03*
X718330Y205172D03*
X704708Y264647D03*
X749620Y273620D03*
X707574Y276558D03*
X712720Y240976D03*
X754227Y297611D03*
X739300Y287611D03*
X751693Y255540D03*
X743507Y251685D03*
X747558Y247274D03*
X759558Y241027D03*
Y247274D03*
X731300Y287611D03*
X735300D03*
X731318Y283571D03*
X735318D03*
X731155Y279636D03*
X739318Y283571D03*
X734638Y275696D03*
X751693Y259540D03*
X755693D03*
X704708Y256647D03*
Y252647D03*
X753560Y273780D03*
X704708Y260647D03*
X721380Y423930D03*
X739680Y423900D03*
X700200Y388200D03*
Y384800D03*
X743480Y439080D03*
X710200Y441200D03*
X706120Y441410D03*
X729870Y451300D03*
X740900Y456400D03*
X700855Y426719D03*
X761650Y89937D03*
X771610Y93040D03*
X799500Y106000D03*
X781000Y88000D03*
Y84200D03*
X788287Y86087D03*
X768250Y106300D03*
X768100Y109700D03*
X763560Y59820D03*
X767359Y82076D03*
X804320Y134300D03*
X804400Y175000D03*
X760800Y169550D03*
X769600Y164200D03*
X765200Y135750D03*
X786500Y134283D03*
X763050Y154100D03*
X761400Y160050D03*
X764600Y141500D03*
X768700Y129800D03*
X768900Y134800D03*
X760715Y197200D03*
X764550Y182900D03*
X764750Y179300D03*
X761550Y180500D03*
X786400Y179000D03*
X779200Y178650D03*
X790714Y237308D03*
X801618Y210116D03*
Y214116D03*
X786006Y283383D03*
X775486Y287316D03*
X781640Y282160D03*
X793837Y291696D03*
X805254Y263886D03*
X761484Y255581D03*
Y251581D03*
X780837Y240885D03*
X774637Y267746D03*
X770637D03*
X761638Y259635D03*
X774637Y259746D03*
Y263746D03*
X793837Y279636D03*
Y275696D03*
X780837Y267826D03*
X784837Y263891D03*
Y259951D03*
X793852Y256011D03*
Y252076D03*
X793837Y271761D03*
Y267826D03*
Y263696D03*
X774657Y255999D03*
X765638Y255635D03*
X774637Y251876D03*
X784837Y271761D03*
Y267826D03*
X793837Y287696D03*
X780837Y271761D03*
X801853Y300515D03*
X767890Y273380D03*
X763292Y287630D03*
X765764Y326844D03*
X801728Y304572D03*
X776497Y338392D03*
X775672Y350204D03*
X782770Y321200D03*
G54D15*
X38502Y161319D03*
X49302D03*
X43902D03*
X49302Y150519D03*
Y155919D03*
X43902Y150519D03*
Y155919D03*
X38502D03*
Y150519D03*
X108672Y138471D03*
Y132871D03*
X90672Y138471D03*
X102672D03*
X96672D03*
X84672D03*
Y132871D03*
X96672D03*
X102672D03*
X90672D03*
G54D16*
X54900Y204700D03*
X49900Y209700D03*
X59900D03*
X54900Y214700D03*
Y209700D03*
G54D24*
X98425Y472441D03*
X137795D03*
G54D31*
X388189Y44095D03*
X374016D03*
X359843D03*
X345670D03*
X388189Y38583D03*
X374016D03*
X359843D03*
X345670D03*
X388189Y29922D03*
X374016D03*
X359843D03*
X345670D03*
X388189Y24410D03*
X374016D03*
X359843D03*
X345670D03*
X388189Y15748D03*
X374016D03*
X359843D03*
X345670D03*
X388189Y10237D03*
X374016D03*
X359843D03*
X345670D03*
X381103Y48819D03*
X366929D03*
X352756D03*
X338583D03*
X381103Y43307D03*
X366929D03*
X352756D03*
X338583D03*
X381103Y34646D03*
X366929D03*
X352756D03*
X338583D03*
X381103Y29134D03*
X366929D03*
X352756D03*
X338583D03*
X381103Y20473D03*
X366929D03*
X352756D03*
X338583D03*
X381103Y14961D03*
X366929D03*
X352756D03*
X338583D03*
X444882Y44095D03*
X430709D03*
X416536D03*
X402363D03*
X444882Y38583D03*
X430709D03*
X416536D03*
X402363D03*
X444882Y29922D03*
X430709D03*
X416536D03*
X402363D03*
X444882Y24410D03*
X430709D03*
X416536D03*
X402363D03*
X444882Y15748D03*
X430709D03*
X416536D03*
X402363D03*
X444882Y10237D03*
X430709D03*
X416536D03*
X402363D03*
X437796Y48819D03*
X423622D03*
X409449D03*
X395276D03*
X437796Y43307D03*
X423622D03*
X409449D03*
X395276D03*
X437796Y34646D03*
X423622D03*
X409449D03*
X395276D03*
X437796Y29134D03*
X423622D03*
X409449D03*
X395276D03*
X437796Y20473D03*
X423622D03*
X409449D03*
X395276D03*
X437796Y14961D03*
X423622D03*
X409449D03*
X395276D03*
X404528Y412795D03*
X413386D03*
X422244D03*
X407480Y422244D03*
X416339D03*
X425197D03*
X407480Y407284D03*
X416339D03*
X425197D03*
X404528Y427756D03*
X413386D03*
X422244D03*
X404528Y442717D03*
X413386D03*
X422244D03*
X404528Y457677D03*
X413386D03*
X422244D03*
X407480Y437205D03*
X416339D03*
X425197D03*
X407480Y452165D03*
X416339D03*
X425197D03*
X501575Y44095D03*
X487402D03*
X473229D03*
X459055D03*
X501575Y38583D03*
X487402D03*
X473229D03*
X459055D03*
X501575Y29922D03*
X487402D03*
X473229D03*
X459055D03*
X501575Y24410D03*
X487402D03*
X473229D03*
X459055D03*
X501575Y15748D03*
X487402D03*
X473229D03*
X459055D03*
X501575Y10237D03*
X487402D03*
X473229D03*
X459055D03*
X508662Y48819D03*
X494489D03*
X480315D03*
X466142D03*
X451969D03*
X508662Y43307D03*
X494489D03*
X480315D03*
X466142D03*
X451969D03*
X508662Y34646D03*
X494489D03*
X480315D03*
X466142D03*
X451969D03*
X508662Y29134D03*
X494489D03*
X480315D03*
X466142D03*
X451969D03*
X508662Y20473D03*
X494489D03*
X480315D03*
X466142D03*
X451969D03*
X508662Y14961D03*
X494489D03*
X480315D03*
X466142D03*
X451969D03*
X572441Y44095D03*
X558268D03*
X544095D03*
X529922D03*
X515748D03*
X572441Y38583D03*
X558268D03*
X544095D03*
X529922D03*
X515748D03*
X572441Y29922D03*
X558268D03*
X544095D03*
X529922D03*
X515748D03*
X572441Y24410D03*
X558268D03*
X544095D03*
X529922D03*
X515748D03*
X572441Y15748D03*
X558268D03*
X544095D03*
X529922D03*
X515748D03*
X572441Y10237D03*
X558268D03*
X544095D03*
X529922D03*
X515748D03*
X565355Y48819D03*
X551181D03*
X537008D03*
X522835D03*
X565355Y43307D03*
X551181D03*
X537008D03*
X522835D03*
X565355Y34646D03*
X551181D03*
X537008D03*
X522835D03*
X565355Y29134D03*
X551181D03*
X537008D03*
X522835D03*
X565355Y20473D03*
X551181D03*
X537008D03*
X522835D03*
X565355Y14961D03*
X551181D03*
X537008D03*
X522835D03*
X586614Y44095D03*
Y38583D03*
Y29922D03*
Y24410D03*
Y15748D03*
Y10237D03*
X579528Y48819D03*
Y43307D03*
Y34646D03*
Y29134D03*
Y20473D03*
Y14961D03*
X758267Y44095D03*
X744094D03*
X729921D03*
X715748D03*
X758267Y38583D03*
X744094D03*
X729921D03*
X715748D03*
X758267Y29922D03*
X744094D03*
X729921D03*
X715748D03*
X758267Y24410D03*
X744094D03*
X729921D03*
X715748D03*
X758267Y15748D03*
X744094D03*
X729921D03*
X715748D03*
X758267Y10237D03*
X744094D03*
X729921D03*
X715748D03*
X751181Y48819D03*
X737007D03*
X722834D03*
X708661D03*
X751181Y43307D03*
X737007D03*
X722834D03*
X708661D03*
X751181Y34646D03*
X737007D03*
X722834D03*
X708661D03*
X751181Y29134D03*
X737007D03*
X722834D03*
X708661D03*
X751181Y20473D03*
X737007D03*
X722834D03*
X708661D03*
X751181Y14961D03*
X737007D03*
X722834D03*
X708661D03*
G54D22*
X128580Y170810D03*
X122984Y170984D03*
X123200Y175800D03*
X125741Y166309D03*
X128459Y175658D03*
X94080Y448470D03*
X198557Y153196D03*
X177850Y324800D03*
X174995Y353588D03*
Y358388D03*
X165195D03*
X169995D03*
Y353588D03*
X197718Y350937D03*
Y355859D03*
X177468Y417900D03*
X142865Y424021D03*
X143608Y415900D03*
X158067Y378857D03*
X176311Y445493D03*
X176423Y440472D03*
X177421Y432909D03*
X177532Y426134D03*
X145392Y445207D03*
X145456Y440338D03*
X142991Y430900D03*
X253600Y139500D03*
Y134700D03*
X251800Y153600D03*
Y144000D03*
Y148800D03*
X258400Y134700D03*
Y139500D03*
X263200Y134700D03*
Y139500D03*
X253600Y230500D03*
Y225700D03*
Y220900D03*
X258400Y230500D03*
Y225700D03*
Y220900D03*
X263200Y230500D03*
Y225700D03*
Y220900D03*
X249204Y244103D03*
X254300Y357732D03*
X246700Y418600D03*
X212589Y494694D03*
X220589D03*
X216589Y489694D03*
X208589D03*
X224589D03*
X295960Y148987D03*
Y154387D03*
X308907Y171800D03*
Y166400D03*
Y161000D03*
X272800Y168000D03*
Y172800D03*
Y134700D03*
X268000Y165962D03*
X268064Y171792D03*
X268000Y158700D03*
Y153900D03*
Y134700D03*
Y139500D03*
Y144300D03*
Y149100D03*
X296200Y195900D03*
Y190500D03*
X308907Y215200D03*
Y220600D03*
Y226000D03*
Y231400D03*
Y236800D03*
Y209800D03*
Y188200D03*
Y199000D03*
Y204400D03*
Y177200D03*
Y193600D03*
Y182800D03*
X296400Y237950D03*
Y232550D03*
X272800Y177600D03*
X268064Y184062D03*
X268000Y235300D03*
Y230500D03*
Y225700D03*
Y220900D03*
Y216000D03*
Y211200D03*
X268118Y191305D03*
X268000Y206400D03*
Y196800D03*
Y201600D03*
Y178062D03*
X308907Y242200D03*
X266404Y249707D03*
X268000Y244900D03*
Y240100D03*
X276070Y395357D03*
X346700Y296333D03*
Y291533D03*
X490877Y185047D03*
Y180547D03*
X510427Y184931D03*
Y180431D03*
X500302Y184989D03*
Y180489D03*
X553500Y231900D03*
X549000D03*
X520552Y184873D03*
Y180373D03*
X550717Y255796D03*
X546217D03*
X550975Y248209D03*
X546475D03*
X551865Y240638D03*
X547365D03*
X570234Y298026D03*
X572634Y293526D03*
X567200Y407700D03*
X572062Y384378D03*
X529500Y471500D03*
X551400Y437800D03*
X545900D03*
X539800Y437900D03*
X576797Y113877D03*
X589706Y174031D03*
X586081Y158407D03*
X585145Y162809D03*
X595402Y149579D03*
X594466Y153981D03*
X588070Y138220D03*
X587134Y142622D03*
X576868Y127381D03*
X575932Y131783D03*
X582554Y116361D03*
X589135Y214107D03*
X588199Y218509D03*
X585010Y198483D03*
X584074Y202885D03*
X580885Y182859D03*
X579949Y187261D03*
X588770Y178433D03*
X575134Y298026D03*
X577534Y293526D03*
X580034Y298026D03*
X632150Y389100D03*
X576862Y384378D03*
X581087Y379569D03*
X576287D03*
X581692Y384378D03*
X605534Y480027D03*
X635000Y427784D03*
X619600Y446100D03*
X629200D03*
X624400D03*
X655964Y52248D03*
X675136Y268500D03*
X637705Y298765D03*
X642705D03*
X696900Y337800D03*
X697500Y358200D03*
X637705Y303765D03*
X642705D03*
X674700Y306300D03*
X679500D03*
Y311100D03*
X674700D03*
X679500Y315900D03*
X674700D03*
X665520Y307707D03*
Y312507D03*
X654642D03*
X654488Y317417D03*
X660100Y307500D03*
X654642Y307707D03*
X665478Y317527D03*
X684400Y400100D03*
X637550Y389050D03*
X655532Y425245D03*
X658032Y420245D03*
X653032D03*
X653200Y408800D03*
X688500Y484400D03*
X675700Y468000D03*
Y463500D03*
X675400Y472300D03*
X659000Y428900D03*
X652200Y429100D03*
X639120Y462230D03*
X688500Y488600D03*
X714600Y338900D03*
Y348500D03*
Y343700D03*
X709800Y348500D03*
Y343700D03*
X706500Y337800D03*
X701700D03*
X707100Y358200D03*
X702300D03*
X722100Y368300D03*
X717300D03*
X712500D03*
X742200Y380400D03*
Y370800D03*
Y375600D03*
X728700Y381000D03*
Y376200D03*
Y371400D03*
X722100Y363500D03*
X717300D03*
X712500D03*
X705900Y386900D03*
X711000Y395100D03*
X710900Y386800D03*
X706000Y395100D03*
X740900Y476400D03*
Y469400D03*
Y461900D03*
X704340Y468062D03*
X705400Y477400D03*
X771083Y211784D03*
G54D33*
X374432Y316002D03*
X425197Y236220D03*
X425196Y228347D03*
X433070Y236221D03*
X440944D03*
X448818D03*
X433070Y228347D03*
X440944D03*
X448818D03*
X405512Y212599D03*
X393701Y208662D03*
X401575D03*
X409449D03*
X417323D03*
X425197D03*
X433071D03*
X440945D03*
X448819D03*
X413386Y212599D03*
X421260D03*
X429134D03*
X437008D03*
X444882D03*
X409449Y232284D03*
X397638Y236221D03*
Y228347D03*
Y224410D03*
X389000Y236100D03*
X401575Y236221D03*
X405512D03*
X417322D03*
X409449Y220473D03*
Y216536D03*
X413386Y220473D03*
Y216536D03*
X417323Y220473D03*
Y216536D03*
X421260Y220473D03*
Y216536D03*
X425197Y220473D03*
Y216536D03*
X429134Y220473D03*
Y216536D03*
X433071Y220473D03*
Y216536D03*
X437008Y220473D03*
Y216536D03*
X440945Y220473D03*
Y216536D03*
X444882Y220473D03*
Y216536D03*
X448819Y220473D03*
Y216536D03*
X409449Y204725D03*
Y200788D03*
X413386Y208662D03*
Y204725D03*
X417323D03*
Y200788D03*
X421260Y208662D03*
Y204725D03*
X425197D03*
Y200788D03*
X429134Y208662D03*
Y204725D03*
X433071D03*
Y200788D03*
X437008Y208662D03*
Y204725D03*
X440945D03*
Y200788D03*
X444882Y208662D03*
Y204725D03*
X448819D03*
Y200788D03*
X389764Y216536D03*
Y212599D03*
X397638Y220473D03*
Y216536D03*
X401575Y220473D03*
Y216536D03*
X405512Y220473D03*
Y216536D03*
X393701Y204725D03*
Y200788D03*
X397638Y208662D03*
Y204725D03*
X401575D03*
Y200788D03*
X405512Y208662D03*
Y204725D03*
X401575Y232284D03*
X401727Y228641D03*
X405512Y232284D03*
X413386D03*
X405512Y228347D03*
X409449Y259843D03*
X425197Y291339D03*
X433071Y295276D03*
Y299213D03*
Y291339D03*
X448819Y287403D03*
X448818Y291339D03*
Y295276D03*
X437008Y299213D03*
Y291339D03*
X429134Y295277D03*
Y299214D03*
X437007Y287402D03*
X429134Y291340D03*
X437008Y275591D03*
X444882D03*
X437007Y267718D03*
X448818Y255906D03*
Y263780D03*
Y271655D03*
X440944Y263780D03*
Y271655D03*
X437007Y259843D03*
Y255905D03*
X440944Y255906D03*
X421260Y259843D03*
X429134Y263781D03*
Y255906D03*
X433071Y283465D03*
X425197Y287402D03*
X444882D03*
X440945Y283465D03*
X448819D03*
X444882Y299213D03*
X425196Y240158D03*
X409449D03*
Y248032D03*
X397638Y244095D03*
X421260Y255906D03*
X425197Y299213D03*
X429134Y287403D03*
X417323Y259843D03*
X413386Y255906D03*
X440945Y295276D03*
Y299213D03*
Y291339D03*
Y287402D03*
X437008Y295276D03*
X429134Y251969D03*
X417323D03*
X413386Y248032D03*
X405512D03*
X421260Y251969D03*
X405512Y244095D03*
X401575D03*
X413386D03*
X417323Y248032D03*
X401575Y240158D03*
X405512D03*
X433070Y287402D03*
X413387Y240158D03*
X421260Y248032D03*
X417323Y244095D03*
X413386Y251969D03*
X401575Y248032D03*
X421260Y295277D03*
X448819Y244095D03*
X440945D03*
X433071D03*
X421259Y240158D03*
X421260Y244095D03*
X417323Y240157D03*
X421260Y299214D03*
X425197Y295276D03*
X413386Y311025D03*
X425197Y318898D03*
Y303150D03*
X429134Y314961D03*
Y311024D03*
X448819Y307088D03*
X448818Y311024D03*
Y303151D03*
X444882Y314961D03*
Y318898D03*
X433071Y314961D03*
X431102Y331263D03*
X429134Y303151D03*
X425197Y314961D03*
X413386Y326772D03*
X425197Y307087D03*
X417323Y314961D03*
X433071Y307087D03*
X448819Y314961D03*
X440945D03*
X417323Y311024D03*
X429134Y318898D03*
X442800Y330300D03*
X446200Y327400D03*
X440945Y303150D03*
Y311024D03*
Y307087D03*
X444881Y322835D03*
X442913Y327204D03*
X440944Y322835D03*
X438976Y327204D03*
X437008Y318898D03*
Y314961D03*
Y311024D03*
Y303150D03*
Y307087D03*
X433071Y318898D03*
X421260Y326772D03*
X421259Y322835D03*
X421260Y318898D03*
Y314961D03*
X417322Y322835D03*
X413386Y314962D03*
X421260Y307088D03*
X433071Y303150D03*
X421260Y303151D03*
X456693Y236221D03*
X464567D03*
X472441D03*
X460630Y208662D03*
X468504D03*
X484252D03*
X476378D03*
X496063D03*
X456693Y212599D03*
X464567D03*
X503937Y216536D03*
X472441Y212599D03*
X480315D03*
X488189D03*
X507874D03*
Y236221D03*
X503937Y232284D03*
X507874Y228347D03*
X503937Y224410D03*
X507874Y220473D03*
X472441Y228347D03*
X464567D03*
X456693D03*
X480315D03*
X484252Y236221D03*
X488189Y232284D03*
X500000Y200788D03*
X503937D03*
X456693Y220473D03*
Y216536D03*
X460630Y220473D03*
Y216536D03*
X464567Y220473D03*
Y216536D03*
X468504Y220473D03*
Y216536D03*
X472441Y220473D03*
Y216536D03*
X476378Y220473D03*
Y216536D03*
X480315Y220473D03*
Y216536D03*
X484252Y220473D03*
Y216536D03*
X488189Y220473D03*
Y216536D03*
X500000Y208662D03*
X503937D03*
X496063Y212599D03*
X500000D03*
X496063Y216536D03*
X500000D03*
X496063Y220473D03*
X500000D03*
X496063Y224410D03*
X500000D03*
X496063Y228347D03*
X500000D03*
X496063Y232284D03*
X500000D03*
X496063Y236221D03*
X500000D03*
X456693Y208662D03*
Y204725D03*
X460630D03*
Y200788D03*
X464567Y208662D03*
Y204725D03*
X468504D03*
Y200788D03*
X472441Y208662D03*
Y204725D03*
X476378D03*
Y200788D03*
X480315Y208662D03*
Y204725D03*
X484252D03*
Y200788D03*
X488189Y208662D03*
Y204725D03*
X468504Y299214D03*
X472442Y287402D03*
X480315Y295276D03*
X484252Y295277D03*
X476378Y291339D03*
X452755Y287402D03*
Y291340D03*
Y295277D03*
X503937Y255906D03*
X507874Y251969D03*
X503937Y248032D03*
X507874Y244095D03*
X503937Y240158D03*
X507874Y271654D03*
X503937Y267717D03*
X507874Y259843D03*
Y287402D03*
X503937Y283465D03*
X507874Y279528D03*
X503937Y275591D03*
Y299213D03*
X507874Y295276D03*
X503937Y291339D03*
X492126Y287402D03*
X484252Y271654D03*
Y279528D03*
X488189Y267717D03*
Y275591D03*
X492126Y271654D03*
Y279528D03*
X488189Y283465D03*
X484252Y259843D03*
Y251969D03*
Y244095D03*
X492126Y259843D03*
Y251969D03*
Y244095D03*
X472441Y291339D03*
X464568Y287402D03*
X460630Y275592D03*
X464568D03*
X452756D03*
X456693Y255906D03*
X464567D03*
Y263780D03*
X456693D03*
X464567Y271655D03*
X456693D03*
X476379Y287402D03*
X472441Y299213D03*
X480315D03*
X488189D03*
X456693Y287402D03*
X460630Y283465D03*
X468504D03*
X468505Y287402D03*
X460631Y295277D03*
X456693Y299213D03*
X460630D03*
X480316Y287403D03*
X484252Y291340D03*
Y287402D03*
X488189Y295276D03*
X456694D03*
X496063Y255906D03*
X500000D03*
X496063Y259843D03*
X500000D03*
X496063Y267717D03*
X500000D03*
X496063Y240158D03*
X500000D03*
X496063Y244095D03*
X500000D03*
X496063Y271654D03*
X500000D03*
X496063Y248032D03*
X500000D03*
X496063Y251969D03*
X500000D03*
X496063Y275591D03*
X500000D03*
X496063Y279528D03*
X500000D03*
X496063Y283465D03*
X500000D03*
X496063Y287402D03*
X500000D03*
X507874Y255906D03*
X511811D03*
Y259843D03*
X507874Y267717D03*
X511811D03*
X507874Y240158D03*
X511811D03*
Y244095D03*
Y271654D03*
X507874Y248032D03*
X511811D03*
Y251969D03*
X507874Y275591D03*
X511811D03*
Y279528D03*
X507874Y283465D03*
X511811D03*
Y287402D03*
X480315Y291339D03*
X496063Y299213D03*
X500000D03*
X496063Y291339D03*
X500000D03*
X496063Y295276D03*
X500000D03*
X476378Y267717D03*
Y275591D03*
Y259843D03*
Y251969D03*
X472441Y244095D03*
X464567D03*
X456693D03*
Y291339D03*
X460630D03*
X500001Y314961D03*
X503937Y318898D03*
X488189Y307087D03*
X492126Y311024D03*
X460630Y307087D03*
X456693D03*
X460630Y311024D03*
X462599Y327204D03*
X456693Y311024D03*
Y314961D03*
X452755Y307087D03*
Y303150D03*
X456693Y318898D03*
X507874Y303150D03*
X484252D03*
X496063Y318898D03*
X488189Y311024D03*
X484252Y307087D03*
Y314961D03*
X476378D03*
X468504D03*
X507874D03*
X492126D03*
X500000Y311025D03*
X460630Y314961D03*
X496063D03*
X476378Y311024D03*
X472441Y307087D03*
X488189Y303150D03*
X500000Y307088D03*
X503937Y311024D03*
X468504Y303151D03*
X460630Y303150D03*
X464567Y303151D03*
X503937Y307087D03*
X507874Y311024D03*
X464567Y307088D03*
X468505D03*
X472441Y314961D03*
X492126Y307087D03*
X496063Y311024D03*
X464567Y311025D03*
Y318898D03*
X472441D03*
X496063Y303150D03*
X500000D03*
X470473Y327204D03*
X468504Y311024D03*
X488189Y322835D03*
X515748Y259843D03*
Y244095D03*
Y271654D03*
Y251969D03*
Y279528D03*
Y287402D03*
X516500Y313000D03*
X682675Y132281D03*
X688974D03*
X660630Y122834D03*
X660629Y119685D03*
X663779Y122834D03*
Y119685D03*
X670079Y122835D03*
X670078Y119685D03*
X673229Y122835D03*
X673228Y119685D03*
X679528Y122835D03*
X679527Y119685D03*
X682678Y122835D03*
X682677Y119685D03*
X688977Y122835D03*
X688976Y119685D03*
X692126Y122835D03*
Y119686D03*
G54D25*
X145669Y25708D03*
Y47362D03*
Y19803D03*
Y31614D03*
Y41456D03*
Y53267D03*
G54D23*
X140000Y204950D03*
X78600Y321700D03*
X78700Y317400D03*
X201400Y174400D03*
X192400D03*
X196900D03*
X179800Y133500D03*
X175800Y129500D03*
X179800D03*
X175800Y133500D03*
X170900Y160500D03*
X151500D03*
X156300D03*
X161100D03*
X165900D03*
X192400Y191600D03*
X196900D03*
X201400D03*
X192400Y187300D03*
X196900D03*
X201400D03*
Y178700D03*
X192400Y183000D03*
X196900D03*
X201400D03*
X192400Y178700D03*
X196900D03*
X151500Y205000D03*
X156300D03*
X161100D03*
X165900D03*
X170900D03*
X178450Y203150D03*
X144800Y204950D03*
X246493Y399567D03*
X242893D03*
X257020Y390670D03*
X253420D03*
X249820D03*
X246220D03*
X256120Y395170D03*
X243120D03*
X247620D03*
X251870D03*
X242620Y390670D03*
X260893Y399567D03*
X257293D03*
X260620Y390670D03*
Y395170D03*
X253693Y399567D03*
X250093D03*
X444882Y279529D03*
X490877Y176547D03*
X510427Y176431D03*
X500302Y176489D03*
X490877Y189047D03*
X510427Y188931D03*
X500302Y188989D03*
X452757Y279529D03*
X520552Y176373D03*
Y188873D03*
X571300Y414800D03*
X527742Y425481D03*
X522942D03*
X518142D03*
X527742Y432481D03*
X522942D03*
X518142D03*
X557411Y481025D03*
X631864Y51848D03*
X618250Y162081D03*
X580900Y414800D03*
X576100D03*
X628113Y428617D03*
X623313D03*
X618513D03*
X613713D03*
X694365Y98458D03*
Y86958D03*
X686279Y98494D03*
Y86994D03*
X678225Y98496D03*
Y86996D03*
X670146Y98505D03*
Y87005D03*
X662047Y98539D03*
Y87039D03*
X654037Y98708D03*
Y87208D03*
X670080Y148030D03*
X694400Y452900D03*
Y457400D03*
Y461900D03*
X689900Y457400D03*
Y452950D03*
X689700Y461850D03*
X710378Y100399D03*
Y88899D03*
X702391Y98510D03*
Y87010D03*
X698900Y457400D03*
X699000Y452950D03*
X698950Y461800D03*
G54D11*
X15364Y5500D03*
X10364D03*
X5500Y10384D03*
Y15384D03*
Y20384D03*
Y25384D03*
Y30384D03*
Y35384D03*
Y40384D03*
Y45384D03*
Y50384D03*
Y55384D03*
Y60384D03*
Y65384D03*
Y70384D03*
Y75384D03*
Y80384D03*
Y85384D03*
Y90384D03*
Y95384D03*
Y100384D03*
Y105384D03*
Y110384D03*
Y115384D03*
Y120384D03*
Y125384D03*
Y130384D03*
Y135384D03*
Y140384D03*
Y145384D03*
Y150384D03*
Y155384D03*
Y160384D03*
Y165384D03*
Y170384D03*
Y175384D03*
Y180384D03*
Y185384D03*
Y190384D03*
Y195384D03*
Y200384D03*
Y205384D03*
Y210384D03*
Y215384D03*
Y220384D03*
Y225384D03*
Y230384D03*
Y235384D03*
Y240384D03*
Y245384D03*
Y250384D03*
Y255384D03*
Y260384D03*
Y265384D03*
Y270384D03*
Y275384D03*
Y280384D03*
Y285384D03*
Y290384D03*
Y295384D03*
Y300384D03*
Y305384D03*
Y310384D03*
Y315384D03*
Y320384D03*
Y325384D03*
Y330384D03*
Y335384D03*
Y340384D03*
Y345384D03*
Y350384D03*
Y355384D03*
Y360384D03*
Y365384D03*
Y370384D03*
Y375384D03*
Y380384D03*
Y385384D03*
Y390384D03*
Y395384D03*
Y400384D03*
Y405384D03*
Y410384D03*
Y415384D03*
Y420384D03*
Y425384D03*
Y430384D03*
Y435384D03*
Y440384D03*
Y445384D03*
Y450384D03*
Y455384D03*
Y460384D03*
Y465384D03*
Y470384D03*
Y475384D03*
Y480384D03*
Y485384D03*
Y530384D03*
Y525384D03*
Y520384D03*
Y515384D03*
Y510384D03*
Y505384D03*
Y490384D03*
Y495384D03*
Y500384D03*
Y535384D03*
Y540384D03*
Y545384D03*
Y550384D03*
Y555384D03*
Y560384D03*
X10266Y565366D03*
X15266D03*
X75364Y5500D03*
X70364D03*
X65364D03*
X60364D03*
X55364D03*
X50364D03*
X45364D03*
X40364D03*
X35364D03*
X30364D03*
X25364D03*
X20364D03*
X21910Y217500D03*
X22250Y223500D03*
X33759Y274180D03*
X37830D03*
X23100Y292200D03*
Y287700D03*
X56026Y256117D03*
X69143Y334598D03*
X47443Y334198D03*
X27947Y334066D03*
X37049Y302949D03*
X23100Y318500D03*
Y314000D03*
X57350Y387800D03*
X46900Y378233D03*
X26100Y378352D03*
X69300Y378800D03*
X31240Y393440D03*
X49700Y391000D03*
X54040Y399390D03*
X20266Y565366D03*
X25266D03*
X30266D03*
X35266D03*
X40266D03*
X45266D03*
X50266D03*
X55266D03*
X60266D03*
X65266D03*
X70266D03*
X75266D03*
X95364Y5500D03*
X90364D03*
X85364D03*
X80364D03*
X81000Y291700D03*
X80896Y286695D03*
X90238Y334391D03*
X89895Y378426D03*
X102850Y452650D03*
X94488Y489888D03*
X80266Y565366D03*
X85266D03*
X90266D03*
X95266D03*
X100266D03*
X105266D03*
X110266D03*
X115266D03*
X120266D03*
X125266D03*
X130266D03*
X135266D03*
X158267Y25708D03*
Y47362D03*
Y53267D03*
Y41456D03*
Y31614D03*
Y19803D03*
X200364Y5500D03*
X195364D03*
X190364D03*
X185364D03*
X180364D03*
X175364D03*
X170364D03*
X191000Y110000D03*
X192830Y170500D03*
X197630D03*
X192830Y165700D03*
X197630D03*
X192830Y160900D03*
X197630D03*
X196963Y122029D03*
X184600Y137400D03*
X195400Y147200D03*
X195500Y142400D03*
X191900Y196100D03*
X196900D03*
X201700D03*
X196900Y200900D03*
X191900D03*
X196900Y205700D03*
X191900D03*
X196900Y210500D03*
X191900D03*
X201700Y205700D03*
Y200900D03*
X200266Y565366D03*
X195266D03*
X190266D03*
X185266D03*
X180266D03*
X175266D03*
X140266D03*
X145266D03*
X150266D03*
X155266D03*
X160266D03*
X165266D03*
X170266D03*
X260364Y5500D03*
X255364D03*
X250364D03*
X245364D03*
X240364D03*
X235364D03*
X230364D03*
X225364D03*
X220364D03*
X215364D03*
X210364D03*
X205364D03*
X242610Y53714D03*
X245250Y98250D03*
X261102Y77900D03*
X223994Y63225D03*
X242727Y63391D03*
X222700Y149300D03*
X227500D03*
X222700Y144500D03*
X227500D03*
X222700Y139700D03*
X227500D03*
X222700Y158900D03*
X227500D03*
X222700Y154100D03*
X227500D03*
X202430Y170500D03*
Y165700D03*
Y160900D03*
X222800Y204600D03*
X227600D03*
X222800Y219000D03*
X227600D03*
X222800Y214200D03*
X227600D03*
X222800Y209400D03*
X227600D03*
X222490Y235373D03*
X227290D03*
X222246Y229952D03*
X227046D03*
X222800Y223800D03*
X227600D03*
X222460Y240264D03*
X227260D03*
X245800Y279200D03*
X207600Y292400D03*
X253575Y320167D03*
X235500Y320100D03*
X218500Y320200D03*
X237600Y390500D03*
X261581Y370979D03*
X209052Y470198D03*
X213700Y448450D03*
X208900D03*
X203000Y451300D03*
X204252Y470198D03*
X204364Y478917D03*
X209164D03*
X205266Y565366D03*
X210266D03*
X215266D03*
X220266D03*
X225266D03*
X230266D03*
X235266D03*
X240266D03*
X245266D03*
X250266D03*
X255266D03*
X260266D03*
X312840Y42398D03*
X325378Y50351D03*
Y35351D03*
X310065Y32397D03*
X325364Y5500D03*
X320364D03*
X315364D03*
X310364D03*
X305364D03*
X300364D03*
X295364D03*
X290364D03*
X285364D03*
X280364D03*
X275364D03*
X270364D03*
X265364D03*
X270000Y29000D03*
Y33500D03*
Y38000D03*
Y42500D03*
X267188Y55192D03*
X285361Y78015D03*
X281761D03*
X289161Y58068D03*
X277514D03*
X287000Y117600D03*
Y125000D03*
X285500Y130400D03*
X290300D03*
X287300Y173000D03*
X292100D03*
X295650Y169554D03*
X295100Y130400D03*
X295801Y210294D03*
X292600Y214500D03*
X287800D03*
X317700Y275400D03*
X270143Y276969D03*
X323681Y259023D03*
X319881D03*
X295879Y255540D03*
X291079D03*
X286279D03*
X284498Y299976D03*
X299635Y292650D03*
X294250Y325000D03*
X277150Y332000D03*
X273165Y320351D03*
X266300Y412100D03*
X265266Y565366D03*
X270266D03*
X275266D03*
X280266D03*
X285266D03*
X290266D03*
X295266D03*
X300266D03*
X305266D03*
X310266D03*
X315266D03*
X320266D03*
X325266D03*
X388189Y48426D03*
X374016D03*
X359843D03*
X345670D03*
X388189Y34252D03*
X374016D03*
X359843D03*
X345670D03*
X388189Y20079D03*
X374016D03*
X359843D03*
X345670D03*
X388189Y5906D03*
X374016D03*
X359843D03*
X345670D03*
X381103Y38977D03*
X366929D03*
X352756D03*
X338583D03*
X381103Y24804D03*
X366929D03*
X352756D03*
X338583D03*
X381103Y53150D03*
X366929D03*
X352756D03*
X338583D03*
X330364Y5500D03*
X341757Y211056D03*
X337157Y206052D03*
X335701Y223995D03*
X352047Y220590D03*
X368714Y261134D03*
X339500Y260400D03*
X327868Y290125D03*
X365996Y287265D03*
Y272841D03*
X366169Y246591D03*
X370669D03*
X338650Y281350D03*
X361996Y272841D03*
X368050Y337200D03*
X370250Y347600D03*
X379148Y337184D03*
X384341Y315377D03*
X377324Y302844D03*
X360050Y337200D03*
X348600Y323900D03*
X359400Y347200D03*
X327365Y433732D03*
X337900Y431200D03*
X350586Y495815D03*
X355523Y495025D03*
X360461Y494236D03*
X365398Y493446D03*
X370335Y492656D03*
X375272Y491866D03*
X380210Y491077D03*
X385169Y490563D03*
X329156Y545492D03*
Y540492D03*
Y535492D03*
Y530492D03*
Y525492D03*
Y520492D03*
Y515492D03*
Y560492D03*
Y555492D03*
Y550492D03*
X444882Y48426D03*
X430709D03*
X416536D03*
X402363D03*
X444882Y34252D03*
X430709D03*
X416536D03*
X402363D03*
X444882Y20079D03*
X430709D03*
X416536D03*
X402363D03*
X444882Y5906D03*
X430709D03*
X416536D03*
X402363D03*
X437796Y38977D03*
X423622D03*
X409449D03*
X395276D03*
X437796Y24804D03*
X423622D03*
X409449D03*
X395276D03*
X437796Y53150D03*
X423622D03*
X409449D03*
X395276D03*
X448818Y232284D03*
X440944D03*
X433070D03*
X433071Y224410D03*
X440945D03*
X448819D03*
X397638Y232284D03*
X389764Y204725D03*
Y220473D03*
Y208662D03*
Y228347D03*
X409449Y236221D03*
X393701Y228347D03*
Y216536D03*
Y212599D03*
X397638D03*
X401575D03*
X393701Y220473D03*
X397638Y200788D03*
X405512D03*
X413386D03*
X421260D03*
X429134D03*
X437008D03*
X444882D03*
X409449Y212599D03*
Y224410D03*
X417323Y212599D03*
X425197D03*
X433071D03*
X440945D03*
X448819D03*
X425197Y224410D03*
X417323D03*
X413386D03*
X433071Y275591D03*
X397638Y240158D03*
Y295276D03*
X405512D03*
X397638Y271654D03*
X409449Y267717D03*
X397638Y287402D03*
X405512D03*
X397638Y279528D03*
X409449Y275591D03*
X397638Y259843D03*
X405512D03*
Y255906D03*
X389764Y251969D03*
X393701D03*
X397638D03*
X409449Y244095D03*
Y255906D03*
X417323Y299213D03*
X421260Y291339D03*
X425197Y259843D03*
X417323Y267717D03*
X429134Y271654D03*
X417323Y275591D03*
X429134Y248032D03*
X425197Y255906D03*
X417323D03*
X413386Y259843D03*
X429134Y279528D03*
X421260D03*
X433071Y240158D03*
Y248032D03*
X448819Y240158D03*
X440945D03*
X448819Y248032D03*
X440945D03*
X444959Y352053D03*
X389559Y337103D03*
X421500Y337500D03*
X427500D03*
X448431Y348737D03*
X397638Y326772D03*
X409449D03*
X397638Y318898D03*
X409449D03*
Y314961D03*
X397638Y311024D03*
X409449D03*
X417323Y326772D03*
Y318898D03*
X425197Y311024D03*
X433071D03*
X397638Y303150D03*
X405512D03*
X413386Y307087D03*
X440945Y318898D03*
X448819D03*
X417323Y307087D03*
Y303150D03*
X410236Y419291D03*
Y404331D03*
Y449212D03*
Y434252D03*
X405169Y490563D03*
X410169D03*
X415169D03*
X420169D03*
X425169D03*
X430169D03*
X435169D03*
X440169D03*
X445146Y490850D03*
X450083Y491640D03*
X390169Y490563D03*
X395169D03*
X400169D03*
X501575Y48426D03*
X487402D03*
X473229D03*
X459055D03*
X501575Y34252D03*
X487402D03*
X473229D03*
X459055D03*
X501575Y20079D03*
X487402D03*
X473229D03*
X459055D03*
X501575Y5906D03*
X487402D03*
X473229D03*
X459055D03*
X508662Y38977D03*
X494489D03*
X480315D03*
X466142D03*
X451969D03*
X508662Y24804D03*
X494489D03*
X480315D03*
X466142D03*
X451969D03*
X508662Y53150D03*
X494489D03*
X480315D03*
X466142D03*
X451969D03*
X456693Y232284D03*
X464567D03*
X472441D03*
X480315D03*
X456693Y200788D03*
X464567D03*
X492126Y208662D03*
Y204725D03*
X500000D03*
X472441Y200788D03*
X480315D03*
X488189D03*
X492126D03*
X460630Y212599D03*
X468504D03*
X492126Y216536D03*
X476378Y212599D03*
X484252D03*
X492126D03*
X503937D03*
X507874Y208662D03*
X503937Y204725D03*
X507874D03*
X503937Y236221D03*
Y228347D03*
X492126Y220473D03*
X503937D03*
X511811Y208662D03*
X507874Y200788D03*
X511811D03*
X472441Y224410D03*
X464567D03*
X456693D03*
X480315D03*
X492126D03*
X488189D03*
X492126Y232284D03*
Y236221D03*
X456693Y279528D03*
X472441Y295276D03*
X503937Y251969D03*
Y244095D03*
Y271654D03*
Y259843D03*
Y287402D03*
Y279528D03*
Y295276D03*
X488189Y287402D03*
X492126Y291339D03*
X488189D03*
X472441Y240158D03*
X456693Y259843D03*
X464567Y240158D03*
X456693D03*
X480315Y267717D03*
Y271654D03*
Y275591D03*
Y279528D03*
Y283465D03*
X492126Y267717D03*
X488189Y271654D03*
X492126Y275591D03*
X488189Y279528D03*
X492126Y283465D03*
X480315Y259843D03*
Y240158D03*
Y244095D03*
Y248032D03*
Y251969D03*
Y255906D03*
X488189Y259843D03*
X492126Y240158D03*
X488189D03*
X492126Y248032D03*
X488189D03*
Y255906D03*
X472441Y275591D03*
Y267717D03*
Y283465D03*
Y259843D03*
Y251969D03*
X456693Y248032D03*
X464567D03*
X481359Y347727D03*
X472441Y303150D03*
X460630Y318898D03*
X468504D03*
X456693Y303150D03*
X476378Y318898D03*
X484252D03*
X492126D03*
X500000D03*
X496063Y307087D03*
X480315Y303150D03*
X492126D03*
X507874Y318898D03*
Y307087D03*
X511811D03*
X503937Y303150D03*
X485100Y366800D03*
X490000Y363700D03*
X502850Y368500D03*
X469832Y494799D03*
X474769Y495589D03*
X455020Y492430D03*
X459958Y493219D03*
X464895Y494009D03*
X497636Y515532D03*
Y520532D03*
Y525532D03*
Y530532D03*
Y535532D03*
Y540532D03*
Y545532D03*
Y550532D03*
Y555532D03*
Y560532D03*
X502550Y565366D03*
X507550D03*
X512550D03*
X572441Y48426D03*
X558268D03*
X544095D03*
X529922D03*
X515748D03*
X572441Y34252D03*
X558268D03*
X544095D03*
X529922D03*
X515748D03*
X572441Y20079D03*
X558268D03*
X544095D03*
X529922D03*
X515748D03*
X572441Y5906D03*
X558268D03*
X544095D03*
X529922D03*
X515748D03*
X565355Y38977D03*
X551181D03*
X537008D03*
X522835D03*
X565355Y24804D03*
X551181D03*
X537008D03*
X522835D03*
X565355Y53150D03*
X551181D03*
X537008D03*
X522835D03*
X557500Y231900D03*
X545000D03*
X517000Y226370D03*
Y218500D03*
Y234252D03*
X554717Y255796D03*
X542217D03*
X554975Y248209D03*
X542475D03*
X555865Y240638D03*
X543365D03*
X517500Y297218D03*
X518647Y288943D03*
X515748Y240158D03*
Y267717D03*
Y255906D03*
Y248032D03*
Y283465D03*
Y275591D03*
Y318898D03*
Y307087D03*
X554250Y457500D03*
X517125Y488975D03*
X517550Y565366D03*
X522550D03*
X527550D03*
X532550D03*
X537550D03*
X542550D03*
X547550D03*
X552550D03*
X557550D03*
X562550D03*
X567550D03*
X572550D03*
X586614Y48426D03*
Y34252D03*
Y20079D03*
Y5906D03*
X579528Y38977D03*
Y24804D03*
Y53150D03*
X591446Y6545D03*
X596446D03*
X601446D03*
X606446D03*
X611446D03*
X616446D03*
X621446D03*
X636446D03*
X631446D03*
X626446D03*
X635942Y97351D03*
X618400Y173443D03*
X617600Y134400D03*
X634000Y234200D03*
X630000D03*
X598600Y247800D03*
Y253100D03*
X633800Y239600D03*
X629900Y239700D03*
X633800Y245700D03*
X629900Y245800D03*
X634100Y252000D03*
X629900D03*
X590050Y337950D03*
X590200Y334350D03*
X627020Y393364D03*
X629770Y369320D03*
X629400Y414324D03*
X630000Y464900D03*
X626300D03*
X577330Y464430D03*
X599900Y438300D03*
X587890Y426720D03*
X577550Y565366D03*
X582550D03*
X587550D03*
X592550D03*
X597550D03*
X602550D03*
X607550D03*
X612550D03*
X617550D03*
X622550D03*
X627550D03*
X632550D03*
X641446Y6545D03*
X646446D03*
X651446D03*
X652551Y40716D03*
X696446Y6545D03*
X691446D03*
X661446D03*
X656446D03*
X686446D03*
X681446D03*
X676446D03*
X671446D03*
X666446D03*
X655914Y39932D03*
X667149Y23411D03*
X637003Y68809D03*
X648207Y70750D03*
X654330Y113385D03*
X688976D03*
X646643Y97859D03*
X644100Y111811D03*
X654330Y154330D03*
X663778Y166928D03*
X673227Y157479D03*
X679526Y144880D03*
X695274Y135431D03*
X698425Y129134D03*
X663778Y160629D03*
Y154330D03*
Y135431D03*
X692124D03*
X673227Y144880D03*
X685825Y138581D03*
X679526D03*
X673227D03*
X666928D03*
X648032Y129134D03*
X657480Y122834D03*
X698425Y135433D03*
Y138582D03*
X692125D03*
X682677Y148031D03*
X688976D03*
X695275D03*
X682677Y154330D03*
X688976D03*
X695275D03*
Y160629D03*
X688976D03*
X682677Y160630D03*
X679527Y163779D03*
X695275Y166929D03*
X688976D03*
X682677D03*
X695275Y173228D03*
X688976D03*
X682677D03*
X654330Y170078D03*
X648031Y163779D03*
X654330D03*
X651181Y157480D03*
X670078Y154330D03*
X644882Y157480D03*
X666929Y125984D03*
X657480Y129134D03*
X651181Y151181D03*
X698425Y116535D03*
X648059Y151191D03*
X685827Y125985D03*
X676377Y116536D03*
X663778Y176377D03*
Y173227D03*
Y170078D03*
X670078Y166928D03*
Y173227D03*
X654330Y176377D03*
X639108Y167800D03*
X648057Y141721D03*
X648032Y135434D03*
Y122835D03*
X660629Y116536D03*
X666929Y116535D03*
X698426Y122835D03*
X692148Y129119D03*
X670116Y132283D03*
X673229Y125985D03*
X679528D03*
X666928Y144880D03*
X651181Y188976D03*
X679527Y182679D03*
Y188975D03*
X692126Y182676D03*
Y185827D03*
Y179527D03*
X697069Y207157D03*
X663400Y234100D03*
X663200Y238100D03*
X682676Y179526D03*
Y188975D03*
X682677Y182677D03*
X682676Y185826D03*
X676377Y201574D03*
Y204723D03*
X685826Y198424D03*
X663778Y182676D03*
Y179526D03*
X654330Y182676D03*
X660629Y192125D03*
X666929D03*
X660630Y198425D03*
X676377Y198424D03*
X685826Y201574D03*
X682677Y192125D03*
X688976D03*
X698425D03*
X640931Y181102D03*
X646594Y210875D03*
X640584Y194127D03*
X695600Y240354D03*
X682700D03*
X695625Y282250D03*
X669125Y280405D03*
X663000Y249200D03*
X663100Y252700D03*
X674841Y262854D03*
X659977Y323082D03*
X664731Y324099D03*
X660115Y351977D03*
Y356777D03*
X664731Y343299D03*
X655500Y360000D03*
X660115Y361577D03*
X664731Y338499D03*
Y333699D03*
Y328899D03*
X659977Y342282D03*
Y332682D03*
Y347082D03*
Y337482D03*
Y327882D03*
X662306Y365477D03*
X657673Y365400D03*
X672281Y378883D03*
X693500Y373300D03*
X694765Y406915D03*
X685750Y419460D03*
X642900Y395400D03*
X694950Y477850D03*
Y473050D03*
X667414Y431956D03*
X637550Y565366D03*
X642550D03*
X647550D03*
X652550D03*
X657550D03*
X662550D03*
X667550D03*
X672550D03*
X677550D03*
X682550D03*
X687550D03*
X692550D03*
X697550D03*
X758267Y48426D03*
X744094D03*
X729921D03*
X715748D03*
X758267Y34252D03*
X744094D03*
X729921D03*
X715748D03*
X758267Y20079D03*
X744094D03*
X729921D03*
X715748D03*
X758267Y5906D03*
X744094D03*
X729921D03*
X715748D03*
X751181Y53150D03*
X737007D03*
X722834D03*
X708661D03*
X751181Y38977D03*
X737007D03*
X722834D03*
X708661D03*
X751181Y24804D03*
X737007D03*
X722834D03*
X708661D03*
X701446Y6545D03*
X728788Y88540D03*
X725295Y88609D03*
X752853Y100900D03*
X733069Y166930D03*
X704725Y135434D03*
X707874Y141732D03*
X701574Y138582D03*
X701575Y135433D03*
X711023Y132283D03*
X704724D03*
X717322Y129133D03*
X726770Y166930D03*
Y173229D03*
X701574Y148031D03*
X707873D03*
X701574Y154330D03*
X707873D03*
Y160629D03*
X701574D03*
X707873Y166929D03*
X701574D03*
X707873Y173228D03*
X701574D03*
X711023Y122834D03*
X717322D03*
X723622D03*
X711023Y141732D03*
X743452Y151815D03*
X714172Y173227D03*
Y144880D03*
Y151180D03*
X717322Y144880D03*
Y151180D03*
X714172Y163778D03*
Y157479D03*
X717322Y163778D03*
Y157479D03*
Y166928D03*
X720472Y173228D03*
Y148031D03*
Y141732D03*
Y160629D03*
Y154330D03*
X720471Y166928D03*
X717322Y141731D03*
X758050Y164050D03*
X704725Y122835D03*
X720472Y135433D03*
X717322Y182676D03*
X711024Y188976D03*
X701575Y182676D03*
X711022Y185825D03*
X701575Y185827D03*
Y179527D03*
X726770Y179528D03*
Y185827D03*
X743200Y227900D03*
X726770Y192126D03*
X730694Y224473D03*
X726656Y235244D03*
X711022Y179526D03*
X714172D03*
X722523Y221315D03*
X720437Y185829D03*
X720472Y179527D03*
Y192125D03*
X711022Y182676D03*
X704724Y192125D03*
X711024D03*
X742200Y340800D03*
Y345600D03*
X737400Y340800D03*
Y345600D03*
X732600Y331200D03*
Y336000D03*
Y340800D03*
Y355200D03*
Y350400D03*
Y345600D03*
X701100Y315900D03*
X705900D03*
X701100Y311100D03*
X705900D03*
Y306300D03*
X701100D03*
X705320Y420610D03*
X735570Y424760D03*
X718110Y442960D03*
X708355Y454712D03*
X719920Y429700D03*
X702550Y565366D03*
X707550D03*
X712550D03*
X717550D03*
X722550D03*
X727550D03*
X732550D03*
X737550D03*
X742550D03*
X747550D03*
X752550D03*
X757550D03*
X821272Y49340D03*
Y44340D03*
Y39340D03*
Y34340D03*
Y29340D03*
Y24340D03*
Y19340D03*
Y14340D03*
Y9340D03*
X815364Y5500D03*
X810364D03*
X805364D03*
X800364D03*
X795364D03*
X790364D03*
X785364D03*
X780364D03*
X775364D03*
X770364D03*
X765364D03*
X799250Y71125D03*
X821272Y114340D03*
Y109340D03*
Y104340D03*
Y99340D03*
Y94340D03*
Y89340D03*
Y84340D03*
Y79340D03*
Y74340D03*
Y69340D03*
Y64340D03*
Y59340D03*
Y54340D03*
X772107Y83046D03*
X799493Y93250D03*
X821272Y174340D03*
Y169340D03*
Y164340D03*
Y159340D03*
Y154340D03*
Y149340D03*
Y144340D03*
Y139340D03*
Y134340D03*
Y129340D03*
Y124340D03*
Y119340D03*
X782500Y134283D03*
X773000Y119600D03*
X776600D03*
X794500Y134283D03*
X785000Y158900D03*
X760600Y173700D03*
X821272Y234340D03*
Y229340D03*
Y224340D03*
Y219340D03*
Y214340D03*
Y209340D03*
Y204340D03*
Y199340D03*
Y194340D03*
Y189340D03*
Y184340D03*
Y179340D03*
X790000Y224700D03*
X795498Y246171D03*
X821272Y299340D03*
Y294340D03*
Y289340D03*
Y284340D03*
Y279340D03*
Y274340D03*
Y269340D03*
Y264340D03*
Y259340D03*
Y254340D03*
Y249340D03*
Y244340D03*
Y239340D03*
X793912Y297020D03*
X793837Y283696D03*
X821272Y359340D03*
Y354340D03*
Y349340D03*
Y344340D03*
Y339340D03*
Y334340D03*
Y329340D03*
Y324340D03*
Y319340D03*
Y314340D03*
Y309340D03*
Y304340D03*
X786610Y321340D03*
X761520Y339110D03*
X821272Y424340D03*
Y419340D03*
Y414340D03*
Y409340D03*
Y404340D03*
Y399340D03*
Y394340D03*
Y389340D03*
Y384340D03*
Y379340D03*
Y374340D03*
Y369340D03*
Y364340D03*
Y484340D03*
Y479340D03*
Y474340D03*
Y469340D03*
Y464340D03*
Y459340D03*
Y454340D03*
Y449340D03*
Y444340D03*
Y439340D03*
Y434340D03*
Y429340D03*
Y504340D03*
Y509340D03*
Y514340D03*
Y519340D03*
Y524340D03*
Y529340D03*
Y549340D03*
Y544340D03*
Y539340D03*
Y534340D03*
Y499340D03*
Y494340D03*
Y489340D03*
X762550Y565366D03*
X767550D03*
X772550D03*
X777550D03*
X782550D03*
X787550D03*
X792550D03*
X797550D03*
X802550D03*
X807550D03*
X812550D03*
X817550D03*
X821272Y559340D03*
Y554340D03*
G54D26*
X145900Y136500D03*
X632750Y295641D03*
Y334300D03*
X688978Y135435D03*
X682679D03*
X676379D03*
X804412Y185332D03*
X800612Y185432D03*
G54D28*
X234450Y73000D03*
X381103Y10651D03*
X366929D03*
X352756D03*
X338583D03*
X437796D03*
X423622D03*
X409449D03*
X395276D03*
X433070Y279528D03*
X508661Y10651D03*
X494488D03*
X480315D03*
X466142D03*
X451969D03*
X565354D03*
X551181D03*
X537008D03*
X522835D03*
X579527D03*
X627455Y185364D03*
X618300Y288745D03*
Y327654D03*
X673229Y166929D03*
Y173228D03*
X660629Y138584D03*
Y141732D03*
X751181Y10651D03*
X737007D03*
X722834D03*
X708661D03*
G54D20*
X116063Y14567D03*
G54D10*
X15812Y-86244D03*
X27058Y25484D03*
X81539Y542850D03*
X411652Y539991D03*
X812711Y-86834D03*
X798456Y26432D03*
G54D34*
X389764Y460630D03*
X437008D03*
G54D21*
X116063Y39075D03*
G54D32*
X374015Y156220D03*
X531496Y371299D03*
X596456Y116142D03*
X781496Y198818D03*
G54D30*
X295275Y531496D03*
X531495D03*
G54D19*
X37402Y535158D03*
X789370D03*
G54D12*
X75119Y111166D03*
X105619D03*
X81119D03*
X87619D03*
X93619D03*
X99619D03*
X83232Y399956D03*
X229000Y95000D03*
X464567Y299214D03*
X751878Y276817D03*
X704115Y414466D03*
Y409666D03*
Y404866D03*
Y400066D03*
X760715Y210200D03*
Y201700D03*
Y214200D03*
X781640Y278660D03*
G54D13*
X22550Y156750D03*
X52400Y237800D03*
X28455Y187767D03*
X28749Y191548D03*
X39301Y203166D03*
X33700Y230600D03*
X222818Y364806D03*
X222909Y371864D03*
X223000Y378246D03*
X296385Y108227D03*
X325651Y439668D03*
X421258Y232283D03*
X448818Y299214D03*
X425196Y283466D03*
X433070Y255905D03*
X401575Y410039D03*
X410433D03*
X419292D03*
X401575Y425000D03*
X410433D03*
X419292D03*
X401575Y439961D03*
X410433D03*
X419292D03*
X401575Y454921D03*
X410433D03*
X419292D03*
X467774Y362151D03*
X467100Y357500D03*
X464500Y347410D03*
X505500Y464400D03*
Y469200D03*
Y474000D03*
X509500Y450800D03*
Y446000D03*
Y441200D03*
X542627Y324049D03*
X555127D03*
X541278Y315738D03*
X553778D03*
X541221Y308771D03*
X553721D03*
X541193Y301280D03*
X553693D03*
X629813Y27661D03*
X634169Y166500D03*
X594025Y284017D03*
X610750Y336850D03*
X594050Y301755D03*
X598152Y370130D03*
X594200Y390400D03*
X609400Y446850D03*
X604400Y456100D03*
Y451850D03*
Y447350D03*
Y460350D03*
X609400Y450450D03*
Y454050D03*
Y457650D03*
Y461250D03*
X599503Y447123D03*
Y450723D03*
Y454323D03*
Y457923D03*
X604400Y464850D03*
X609400D03*
X599503Y461523D03*
Y465123D03*
X656450Y28000D03*
X657480Y151219D03*
X676379Y182678D03*
Y192126D03*
X670080Y182678D03*
X672800Y438832D03*
X696950Y441400D03*
X751133Y313984D03*
X754227Y301111D03*
X725247Y458974D03*
X724422Y464139D03*
X724400Y485200D03*
Y480400D03*
Y475600D03*
X701120Y430620D03*
X724400Y490200D03*
G54D35*
X448818Y259843D03*
Y267718D03*
X440944D03*
Y259843D03*
X456693Y267718D03*
X464567D03*
Y279529D03*
Y259843D03*
G54D27*
X157650Y418100D03*
X160400Y422900D03*
X160550Y414100D03*
X160400Y427700D03*
Y432500D03*
X786300Y309900D03*
G54D29*
X248169Y74454D03*
X437057Y279414D03*
X632750Y292195D03*
Y330854D03*
X632900Y344950D03*
X612300Y356850D03*
X608500Y315000D03*
X634000Y306300D03*
G54D36*
X433071Y263781D03*
G54D37*
X590537Y170119D03*
X586912Y154495D03*
X584314Y166721D03*
X596233Y145667D03*
X593635Y157893D03*
X588901Y134308D03*
X586303Y146534D03*
X577699Y123469D03*
X575101Y135695D03*
X589966Y210195D03*
X587368Y222421D03*
X585841Y194571D03*
X583243Y206797D03*
X581716Y178947D03*
X579118Y191173D03*
X587939Y182345D03*
G54D18*
X37402Y499724D03*
X789370D03*
%LPC*%
G75*
G54D38*
G01X-34018Y-300855D02*
G02I-12000J0D01*
G01X-39168D02*
G02I-6850J0D01*
G01X-30018D02*
X-62018D01*
G01X-30018Y-316855D02*
Y-396855D01*
G01D02*
X1320682D01*
G01X-30018Y-352355D02*
X1320682D01*
G01X-46018Y-316855D02*
Y-284855D01*
G01X-30018Y-316855D02*
X1320682D01*
G01X533182D02*
Y-396855D01*
G01X670682Y-316855D02*
Y-396855D01*
G01X785682Y-316855D02*
Y-396855D01*
G01X953182Y-316855D02*
Y-396855D01*
G01X1123182Y-316855D02*
Y-396855D01*
G01X1320682Y-316855D02*
Y-396855D01*
G01X1348682Y-300855D02*
G02I-12000J0D01*
G01X1343532D02*
G02I-6850J0D01*
G01X1336682Y-316855D02*
Y-284855D01*
G01X1352682Y-300855D02*
X1320682D01*
G54D39*
G01X121778Y-377522D02*
X122652Y-376647D01*
X123307Y-375189D01*
X123744Y-373146D01*
X123307Y-371397D01*
X122434Y-370230D01*
X120905Y-369355D01*
X115010D01*
Y-386855D01*
X122215D01*
X123744Y-385689D01*
X124617Y-383938D01*
X125054Y-381897D01*
X124617Y-379855D01*
X123307Y-378105D01*
X121778Y-377522D01*
X115010D01*
G01X134475Y-386855D02*
Y-375189D01*
G01Y-377522D02*
X135567Y-376355D01*
X136659Y-375480D01*
X138187Y-375189D01*
X139278Y-375480D01*
X140589Y-376355D01*
G01X150447Y-392105D02*
X151757Y-392688D01*
X153504Y-392105D01*
X154595Y-390939D01*
X155469Y-389480D01*
X156778Y-384814D01*
X159617Y-375189D01*
G01X152630D02*
X156778Y-384814D01*
G01X176025Y-376647D02*
X174497Y-375480D01*
X173187Y-375189D01*
X171440Y-375772D01*
X170130Y-376938D01*
X169257Y-378980D01*
X169038Y-381022D01*
X169257Y-383064D01*
X170130Y-384814D01*
X171440Y-386272D01*
X173187Y-386855D01*
X174715Y-386272D01*
X176025Y-385105D01*
G01X186757Y-378980D02*
X193744D01*
X193089Y-376938D01*
X191997Y-375772D01*
X190469Y-375189D01*
X188940Y-375480D01*
X187630Y-376355D01*
X186757Y-378397D01*
X186320Y-380147D01*
Y-381897D01*
X186757Y-383647D01*
X187849Y-385397D01*
X189159Y-386563D01*
X190687Y-386855D01*
X192215Y-386272D01*
X193744Y-384522D01*
G01X229835Y-370814D02*
X228525Y-369938D01*
X226997Y-369355D01*
X225250D01*
X223285Y-370230D01*
X221757Y-371688D01*
X220665Y-373439D01*
X219792Y-376355D01*
X219573Y-378980D01*
X220010Y-381605D01*
X220665Y-383355D01*
X221975Y-385105D01*
X223504Y-386272D01*
X225032Y-386855D01*
X226560D01*
X228089Y-386272D01*
X229399Y-385397D01*
X230491Y-384231D01*
G01X246462Y-386855D02*
Y-375189D01*
G01Y-377230D02*
X245589Y-376064D01*
X244278Y-375480D01*
X242750Y-375189D01*
X241222Y-375772D01*
X239912Y-376938D01*
X239038Y-378688D01*
X238602Y-381022D01*
X239038Y-383355D01*
X239912Y-385105D01*
X241222Y-386272D01*
X242750Y-386855D01*
X244278Y-386563D01*
X245589Y-385689D01*
X246462Y-384522D01*
G01X256320Y-386855D02*
Y-375189D01*
G01Y-378105D02*
X257194Y-376647D01*
X258504Y-375480D01*
X260250Y-375189D01*
X261778Y-375480D01*
X263089Y-376647D01*
X263744Y-378688D01*
Y-386855D01*
G01X272947Y-392105D02*
X274257Y-392688D01*
X276004Y-392105D01*
X277095Y-390939D01*
X277969Y-389480D01*
X279278Y-384814D01*
X282117Y-375189D01*
G01X275130D02*
X279278Y-384814D01*
G01X295032Y-386855D02*
X293722Y-386563D01*
X292412Y-385397D01*
X291538Y-383355D01*
X291102Y-381022D01*
X291538Y-378688D01*
X292412Y-376647D01*
X293722Y-375480D01*
X295032Y-375189D01*
X296342Y-375480D01*
X297652Y-376647D01*
X298525Y-378688D01*
X298744Y-381022D01*
X298525Y-383355D01*
X297652Y-385397D01*
X296342Y-386563D01*
X295032Y-386855D01*
G01X308820D02*
Y-375189D01*
G01Y-378105D02*
X309694Y-376647D01*
X311004Y-375480D01*
X312750Y-375189D01*
X314278Y-375480D01*
X315589Y-376647D01*
X316244Y-378688D01*
Y-386855D01*
G01X342947Y-384522D02*
X344694Y-385980D01*
X346659Y-386855D01*
X348405D01*
X350152Y-385980D01*
X351462Y-384522D01*
X352117Y-382480D01*
X351680Y-380439D01*
X350589Y-378688D01*
X348624Y-377522D01*
X346004Y-376938D01*
X344475Y-375772D01*
X343820Y-373730D01*
X344257Y-371688D01*
X345349Y-370230D01*
X346877Y-369355D01*
X348405D01*
X349934Y-369938D01*
X351244Y-371397D01*
G01X369835Y-370814D02*
X368525Y-369938D01*
X366997Y-369355D01*
X365250D01*
X363285Y-370230D01*
X361757Y-371688D01*
X360665Y-373439D01*
X359792Y-376355D01*
X359573Y-378980D01*
X360010Y-381605D01*
X360665Y-383355D01*
X361975Y-385105D01*
X363504Y-386272D01*
X365032Y-386855D01*
X366560D01*
X368089Y-386272D01*
X369399Y-385397D01*
X370491Y-384231D01*
G01X387335Y-370814D02*
X386025Y-369938D01*
X384497Y-369355D01*
X382750D01*
X380785Y-370230D01*
X379257Y-371688D01*
X378165Y-373439D01*
X377292Y-376355D01*
X377073Y-378980D01*
X377510Y-381605D01*
X378165Y-383355D01*
X379475Y-385105D01*
X381004Y-386272D01*
X382532Y-386855D01*
X384060D01*
X385589Y-386272D01*
X386899Y-385397D01*
X387991Y-384231D01*
G01X210605Y-341855D02*
Y-324355D01*
X216282Y-338938D01*
X221959Y-324355D01*
Y-341855D01*
G01X233782D02*
X232472Y-341563D01*
X231162Y-340397D01*
X230288Y-338355D01*
X229852Y-336022D01*
X230288Y-333688D01*
X231162Y-331647D01*
X232472Y-330480D01*
X233782Y-330189D01*
X235092Y-330480D01*
X236402Y-331647D01*
X237275Y-333688D01*
X237494Y-336022D01*
X237275Y-338355D01*
X236402Y-340397D01*
X235092Y-341563D01*
X233782Y-341855D01*
G01X255212Y-324355D02*
Y-341855D01*
G01Y-339231D02*
X254339Y-340689D01*
X253028Y-341563D01*
X251500Y-341855D01*
X249754Y-341272D01*
X248444Y-339814D01*
X247570Y-338064D01*
X247352Y-336022D01*
X247570Y-333980D01*
X248444Y-332230D01*
X249754Y-330772D01*
X251500Y-330189D01*
X253028Y-330480D01*
X254120Y-331064D01*
X255212Y-332230D01*
G01X265507Y-333980D02*
X272494D01*
X271839Y-331938D01*
X270747Y-330772D01*
X269219Y-330189D01*
X267690Y-330480D01*
X266380Y-331355D01*
X265507Y-333397D01*
X265070Y-335147D01*
Y-336897D01*
X265507Y-338647D01*
X266599Y-340397D01*
X267909Y-341563D01*
X269437Y-341855D01*
X270965Y-341272D01*
X272494Y-339522D01*
G01X286282Y-341855D02*
Y-324355D01*
G01X566882Y-386855D02*
Y-369355D01*
X564262Y-372855D01*
G01Y-386855D02*
X569502D01*
G01X580234Y-379564D02*
X581762Y-377522D01*
X583072Y-376355D01*
X584819Y-375772D01*
X586347Y-376355D01*
X587439Y-377522D01*
X588312Y-379272D01*
X588530Y-381313D01*
X588312Y-383064D01*
X587439Y-384814D01*
X586128Y-386272D01*
X584600Y-386855D01*
X582854Y-386272D01*
X581325Y-384522D01*
X580452Y-381897D01*
X580234Y-378980D01*
X580670Y-375189D01*
X581325Y-373146D01*
X582417Y-371105D01*
X583945Y-369647D01*
X585474Y-369355D01*
X587002Y-369938D01*
X588094Y-371397D01*
G01X597079Y-383355D02*
X598388Y-385397D01*
X600135Y-386563D01*
X602100Y-386855D01*
X603847Y-386563D01*
X605594Y-385105D01*
X606685Y-383355D01*
X606904Y-381605D01*
X606467Y-379564D01*
X604939Y-378105D01*
X603410Y-377522D01*
X601445D01*
G01X603410D02*
X604720Y-376647D01*
X605812Y-375189D01*
X606249Y-373439D01*
X605812Y-371688D01*
X604720Y-370230D01*
X602755Y-369355D01*
X600790Y-369647D01*
X598825Y-370814D01*
G01X619382Y-386855D02*
Y-369355D01*
X616762Y-372855D01*
G01Y-386855D02*
X622002D01*
G01X632734Y-379564D02*
X634262Y-377522D01*
X635572Y-376355D01*
X637319Y-375772D01*
X638847Y-376355D01*
X639939Y-377522D01*
X640812Y-379272D01*
X641030Y-381313D01*
X640812Y-383064D01*
X639939Y-384814D01*
X638628Y-386272D01*
X637100Y-386855D01*
X635354Y-386272D01*
X633825Y-384522D01*
X632952Y-381897D01*
X632734Y-378980D01*
X633170Y-375189D01*
X633825Y-373146D01*
X634917Y-371105D01*
X636445Y-369647D01*
X637974Y-369355D01*
X639502Y-369938D01*
X640594Y-371397D01*
G01X553765Y-341855D02*
Y-324355D01*
X559005D01*
X560752Y-325230D01*
X562062Y-327272D01*
X562499Y-329605D01*
X562062Y-331938D01*
X560970Y-333688D01*
X559005Y-334564D01*
X553765D01*
G01X580435Y-325814D02*
X579125Y-324938D01*
X577597Y-324355D01*
X575850D01*
X573885Y-325230D01*
X572357Y-326688D01*
X571265Y-328439D01*
X570392Y-331355D01*
X570173Y-333980D01*
X570610Y-336605D01*
X571265Y-338355D01*
X572575Y-340105D01*
X574104Y-341272D01*
X575632Y-341855D01*
X577160D01*
X578689Y-341272D01*
X579999Y-340397D01*
X581091Y-339231D01*
G01X594878Y-332522D02*
X595752Y-331647D01*
X596407Y-330189D01*
X596844Y-328146D01*
X596407Y-326397D01*
X595534Y-325230D01*
X594005Y-324355D01*
X588110D01*
Y-341855D01*
X595315D01*
X596844Y-340689D01*
X597717Y-338938D01*
X598154Y-336897D01*
X597717Y-334855D01*
X596407Y-333105D01*
X594878Y-332522D01*
X588110D01*
G01X604082Y-347688D02*
X617182D01*
G01X623110Y-341855D02*
Y-324355D01*
X633154Y-341855D01*
Y-324355D01*
G01X645632Y-341855D02*
X643885Y-341563D01*
X642357Y-340397D01*
X641047Y-338647D01*
X640173Y-336605D01*
X639737Y-334272D01*
Y-331938D01*
X640173Y-329605D01*
X641047Y-327563D01*
X642357Y-325814D01*
X643885Y-324647D01*
X645632Y-324355D01*
X647378Y-324647D01*
X648907Y-325814D01*
X650217Y-327563D01*
X651091Y-329605D01*
X651527Y-331938D01*
Y-334272D01*
X651091Y-336605D01*
X650217Y-338647D01*
X648907Y-340397D01*
X647378Y-341563D01*
X645632Y-341855D01*
G01X696473Y-324355D02*
X701932Y-341855D01*
X707391Y-324355D01*
G01X723799Y-341855D02*
X715065D01*
Y-324355D01*
X723799D01*
G01X720305Y-332813D02*
X715065D01*
G01X732565Y-341855D02*
Y-324355D01*
X738024D01*
X739770Y-325230D01*
X740862Y-326397D01*
X741299Y-328730D01*
X740862Y-331064D01*
X739552Y-332522D01*
X738024Y-333397D01*
X732565D01*
G01X738024D02*
X741299Y-341855D01*
G01X754432Y-342438D02*
X753995Y-342147D01*
Y-341563D01*
X754432Y-341272D01*
X754869Y-341563D01*
Y-342147D01*
X754432Y-342438D01*
G01X728182Y-386855D02*
Y-369355D01*
X725562Y-372855D01*
G01Y-386855D02*
X730802D01*
G01X908749Y-369355D02*
Y-386855D01*
X900015D01*
G01X887319D02*
X886882Y-383064D01*
X886227Y-379855D01*
X885354Y-376938D01*
X884262Y-373730D01*
X882515Y-369355D01*
X891249D01*
G01X868072Y-378105D02*
X863705D01*
Y-383355D01*
X865015Y-385105D01*
X866544Y-386272D01*
X868727Y-386855D01*
X870910Y-386272D01*
X872439Y-385105D01*
X873749Y-383355D01*
X874622Y-381313D01*
X875059Y-378980D01*
Y-376938D01*
X874622Y-375189D01*
X873749Y-373146D01*
X872439Y-371397D01*
X871129Y-370230D01*
X869382Y-369355D01*
X867854D01*
X866107Y-369938D01*
X864797Y-371105D01*
G01X856904Y-386855D02*
Y-369355D01*
X846860Y-386855D01*
Y-369355D01*
G01X839185Y-386855D02*
Y-369355D01*
X834819D01*
X833072Y-370230D01*
X831762Y-371397D01*
X830670Y-373146D01*
X829797Y-375189D01*
X829579Y-378105D01*
X829797Y-381022D01*
X830670Y-383064D01*
X831762Y-384814D01*
X833072Y-385980D01*
X834819Y-386855D01*
X839185D01*
G01X830015Y-324355D02*
Y-341855D01*
X838749D01*
G01X855812D02*
Y-330189D01*
G01Y-332230D02*
X854939Y-331064D01*
X853628Y-330480D01*
X852100Y-330189D01*
X850572Y-330772D01*
X849262Y-331938D01*
X848388Y-333688D01*
X847952Y-336022D01*
X848388Y-338355D01*
X849262Y-340105D01*
X850572Y-341272D01*
X852100Y-341855D01*
X853628Y-341563D01*
X854939Y-340689D01*
X855812Y-339522D01*
G01X864797Y-347105D02*
X866107Y-347688D01*
X867854Y-347105D01*
X868945Y-345939D01*
X869819Y-344480D01*
X871128Y-339814D01*
X873967Y-330189D01*
G01X866980D02*
X871128Y-339814D01*
G01X883607Y-333980D02*
X890594D01*
X889939Y-331938D01*
X888847Y-330772D01*
X887319Y-330189D01*
X885790Y-330480D01*
X884480Y-331355D01*
X883607Y-333397D01*
X883170Y-335147D01*
Y-336897D01*
X883607Y-338647D01*
X884699Y-340397D01*
X886009Y-341563D01*
X887537Y-341855D01*
X889065Y-341272D01*
X890594Y-339522D01*
G01X901325Y-341855D02*
Y-330189D01*
G01Y-332522D02*
X902417Y-331355D01*
X903509Y-330480D01*
X905037Y-330189D01*
X906128Y-330480D01*
X907439Y-331355D01*
G01X994432Y-386855D02*
X992685Y-386563D01*
X991157Y-385397D01*
X989847Y-383647D01*
X988973Y-381605D01*
X988537Y-379272D01*
Y-376938D01*
X988973Y-374605D01*
X989847Y-372563D01*
X991157Y-370814D01*
X992685Y-369647D01*
X994432Y-369355D01*
X996178Y-369647D01*
X997707Y-370814D01*
X999017Y-372563D01*
X999891Y-374605D01*
X1000327Y-376938D01*
Y-379272D01*
X999891Y-381605D01*
X999017Y-383647D01*
X997707Y-385397D01*
X996178Y-386563D01*
X994432Y-386855D01*
G01X996178Y-382188D02*
X998799Y-386855D01*
G01X1007129Y-369355D02*
Y-381897D01*
X1008002Y-384522D01*
X1009749Y-386272D01*
X1011932Y-386855D01*
X1014115Y-386272D01*
X1015862Y-384522D01*
X1016735Y-381897D01*
Y-369355D01*
G01X1026812D02*
X1032052D01*
G01X1029432D02*
Y-386855D01*
G01X1026812D02*
X1032052D01*
G01X1041910D02*
Y-369355D01*
X1051954Y-386855D01*
Y-369355D01*
G01X1069235Y-370814D02*
X1067925Y-369938D01*
X1066397Y-369355D01*
X1064650D01*
X1062685Y-370230D01*
X1061157Y-371688D01*
X1060065Y-373439D01*
X1059192Y-376355D01*
X1058973Y-378980D01*
X1059410Y-381605D01*
X1060065Y-383355D01*
X1061375Y-385105D01*
X1062904Y-386272D01*
X1064432Y-386855D01*
X1065960D01*
X1067489Y-386272D01*
X1068799Y-385397D01*
X1069891Y-384231D01*
G01X1081932Y-386855D02*
Y-378980D01*
X1077565Y-369355D01*
G01X1086299D02*
X1081932Y-378980D01*
G01X972129Y-341855D02*
Y-324355D01*
X976495D01*
X978242Y-325230D01*
X979552Y-326397D01*
X980644Y-328146D01*
X981517Y-330189D01*
X981735Y-333105D01*
X981517Y-336022D01*
X980644Y-338064D01*
X979552Y-339814D01*
X978242Y-340980D01*
X976495Y-341855D01*
X972129D01*
G01X991157Y-333980D02*
X998144D01*
X997489Y-331938D01*
X996397Y-330772D01*
X994869Y-330189D01*
X993340Y-330480D01*
X992030Y-331355D01*
X991157Y-333397D01*
X990720Y-335147D01*
Y-336897D01*
X991157Y-338647D01*
X992249Y-340397D01*
X993559Y-341563D01*
X995087Y-341855D01*
X996615Y-341272D01*
X998144Y-339522D01*
G01X1008657Y-339814D02*
X1009749Y-340980D01*
X1011277Y-341855D01*
X1012587D01*
X1013897Y-341272D01*
X1014770Y-340397D01*
X1015207Y-339231D01*
X1014989Y-337480D01*
X1014115Y-336605D01*
X1010185Y-334855D01*
X1009312Y-332813D01*
X1009749Y-331355D01*
X1010622Y-330480D01*
X1011932Y-330189D01*
X1013242Y-330480D01*
X1014552Y-331355D01*
G01X1029432Y-330189D02*
Y-341855D01*
G01Y-325522D02*
X1028995Y-325230D01*
Y-324647D01*
X1029432Y-324355D01*
X1029869Y-324647D01*
Y-325230D01*
X1029432Y-325522D01*
G01X1043875Y-346230D02*
X1045404Y-347397D01*
X1047150Y-347688D01*
X1048678Y-347397D01*
X1049989Y-345939D01*
X1050862Y-343897D01*
Y-330189D01*
G01Y-332522D02*
X1049989Y-331355D01*
X1048678Y-330480D01*
X1047150Y-330189D01*
X1045404Y-330772D01*
X1044312Y-331938D01*
X1043438Y-333980D01*
X1043002Y-336022D01*
X1043220Y-337772D01*
X1044094Y-339814D01*
X1045404Y-341272D01*
X1047150Y-341855D01*
X1048460Y-341563D01*
X1049989Y-340397D01*
X1050862Y-339231D01*
G01X1060720Y-341855D02*
Y-330189D01*
G01Y-333105D02*
X1061594Y-331647D01*
X1062904Y-330480D01*
X1064650Y-330189D01*
X1066178Y-330480D01*
X1067489Y-331647D01*
X1068144Y-333688D01*
Y-341855D01*
G01X1078657Y-333980D02*
X1085644D01*
X1084989Y-331938D01*
X1083897Y-330772D01*
X1082369Y-330189D01*
X1080840Y-330480D01*
X1079530Y-331355D01*
X1078657Y-333397D01*
X1078220Y-335147D01*
Y-336897D01*
X1078657Y-338647D01*
X1079749Y-340397D01*
X1081059Y-341563D01*
X1082587Y-341855D01*
X1084115Y-341272D01*
X1085644Y-339522D01*
G01X1096375Y-341855D02*
Y-330189D01*
G01Y-332522D02*
X1097467Y-331355D01*
X1098559Y-330480D01*
X1100087Y-330189D01*
X1101178Y-330480D01*
X1102489Y-331355D01*
G01X1143132Y-369355D02*
X1141385Y-369938D01*
X1140075Y-371397D01*
X1139202Y-373146D01*
X1138547Y-375480D01*
X1138329Y-378105D01*
X1138547Y-380730D01*
X1139202Y-383064D01*
X1140075Y-384814D01*
X1141385Y-386272D01*
X1143132Y-386855D01*
X1144878Y-386272D01*
X1146189Y-384814D01*
X1147062Y-383064D01*
X1147717Y-380730D01*
X1147935Y-378105D01*
X1147717Y-375480D01*
X1147062Y-373146D01*
X1146189Y-371397D01*
X1144878Y-369938D01*
X1143132Y-369355D01*
G01X1156484Y-379564D02*
X1158012Y-377522D01*
X1159322Y-376355D01*
X1161069Y-375772D01*
X1162597Y-376355D01*
X1163689Y-377522D01*
X1164562Y-379272D01*
X1164780Y-381313D01*
X1164562Y-383064D01*
X1163689Y-384814D01*
X1162378Y-386272D01*
X1160850Y-386855D01*
X1159104Y-386272D01*
X1157575Y-384522D01*
X1156702Y-381897D01*
X1156484Y-378980D01*
X1156920Y-375189D01*
X1157575Y-373146D01*
X1158667Y-371105D01*
X1160195Y-369647D01*
X1161724Y-369355D01*
X1163252Y-369938D01*
X1164344Y-371397D01*
G01X1174202Y-387438D02*
X1182062Y-369355D01*
G01X1191484Y-372272D02*
X1192794Y-370522D01*
X1194322Y-369647D01*
X1196069Y-369355D01*
X1198252Y-369938D01*
X1199780Y-371397D01*
X1200217Y-373146D01*
X1199999Y-374897D01*
X1199125Y-376355D01*
X1194759Y-379272D01*
X1192794Y-381313D01*
X1191484Y-384231D01*
X1191047Y-386855D01*
X1200217D01*
G01X1213132D02*
Y-369355D01*
X1210512Y-372855D01*
G01Y-386855D02*
X1215752D01*
G01X1226702Y-387438D02*
X1234562Y-369355D01*
G01X1243984Y-372272D02*
X1245294Y-370522D01*
X1246822Y-369647D01*
X1248569Y-369355D01*
X1250752Y-369938D01*
X1252280Y-371397D01*
X1252717Y-373146D01*
X1252499Y-374897D01*
X1251625Y-376355D01*
X1247259Y-379272D01*
X1245294Y-381313D01*
X1243984Y-384231D01*
X1243547Y-386855D01*
X1252717D01*
G01X1265632Y-369355D02*
X1263885Y-369938D01*
X1262575Y-371397D01*
X1261702Y-373146D01*
X1261047Y-375480D01*
X1260829Y-378105D01*
X1261047Y-380730D01*
X1261702Y-383064D01*
X1262575Y-384814D01*
X1263885Y-386272D01*
X1265632Y-386855D01*
X1267378Y-386272D01*
X1268689Y-384814D01*
X1269562Y-383064D01*
X1270217Y-380730D01*
X1270435Y-378105D01*
X1270217Y-375480D01*
X1269562Y-373146D01*
X1268689Y-371397D01*
X1267378Y-369938D01*
X1265632Y-369355D01*
G01X1283132Y-386855D02*
Y-369355D01*
X1280512Y-372855D01*
G01Y-386855D02*
X1285752D01*
G01X1300195D02*
X1300632Y-383064D01*
X1301287Y-379855D01*
X1302160Y-376938D01*
X1303252Y-373730D01*
X1304999Y-369355D01*
X1296265D01*
G01X1190829Y-341855D02*
Y-324355D01*
X1195195D01*
X1196942Y-325230D01*
X1198252Y-326397D01*
X1199344Y-328146D01*
X1200217Y-330189D01*
X1200435Y-333105D01*
X1200217Y-336022D01*
X1199344Y-338064D01*
X1198252Y-339814D01*
X1196942Y-340980D01*
X1195195Y-341855D01*
X1190829D01*
G01X1217062D02*
Y-330189D01*
G01Y-332230D02*
X1216189Y-331064D01*
X1214878Y-330480D01*
X1213350Y-330189D01*
X1211822Y-330772D01*
X1210512Y-331938D01*
X1209638Y-333688D01*
X1209202Y-336022D01*
X1209638Y-338355D01*
X1210512Y-340105D01*
X1211822Y-341272D01*
X1213350Y-341855D01*
X1214878Y-341563D01*
X1216189Y-340689D01*
X1217062Y-339522D01*
G01X1230632Y-324355D02*
Y-341855D01*
G01X1227575Y-330189D02*
X1233689D01*
G01X1244857Y-333980D02*
X1251844D01*
X1251189Y-331938D01*
X1250097Y-330772D01*
X1248569Y-330189D01*
X1247040Y-330480D01*
X1245730Y-331355D01*
X1244857Y-333397D01*
X1244420Y-335147D01*
Y-336897D01*
X1244857Y-338647D01*
X1245949Y-340397D01*
X1247259Y-341563D01*
X1248787Y-341855D01*
X1250315Y-341272D01*
X1251844Y-339522D01*
M02*
